FILE_TYPE = MACRO_DRAWING;
SET COLOR_WIRE YELLOW;
SET COLOR_PROP ORANGE;
SET COLOR_DOT WHITE;
SET COLOR_ARC YELLOW;
SET COLOR_BODY GREEN;
SET COLOR_NOTE PURPLE;
SET PROP_DISPLAY VALUE;
SET PAGE_NUMBER P287;
FORCEADD UNIVERSAL_GND..1
(-2900 -525);
FORCEPROP 3 LASTPIN (-2900 -475) SIG_NAME DELTA_L_GND_1\g
J 0
(-2890 -465);
DISPLAY 0.659574 (-2890 -465);
PAINT MONO (-2890 -465);
DISPLAY INVISIBLE (-2890 -465);
FORCEPROP 1 LAST HDL_POWER DELTA_L_GND_1
J 1
(-2875 -600);
DISPLAY 0.872340 (-2875 -600);
PAINT GREEN (-2875 -600);
FORCEPROP 2 LAST CDS_LIB logical_power
J 0
(-2900 -525);
DISPLAY INVISIBLE (-2900 -525);
FORCEPROP 1 LAST PATH I1
J 0
(-2825 -525);
DISPLAY 0.872340 (-2825 -525);
PAINT AQUA (-2825 -525);
DISPLAY INVISIBLE (-2825 -525);
FORCEADD UNIVERSAL_GND..1
(-2950 2300);
FORCEPROP 3 LASTPIN (-2950 2350) SIG_NAME DELTA_L_GND_1\g
J 0
(-2940 2360);
DISPLAY 0.659574 (-2940 2360);
PAINT MONO (-2940 2360);
DISPLAY INVISIBLE (-2940 2360);
FORCEPROP 1 LAST HDL_POWER DELTA_L_GND_1
J 1
(-2925 2225);
DISPLAY 0.872340 (-2925 2225);
PAINT GREEN (-2925 2225);
FORCEPROP 2 LAST CDS_LIB logical_power
J 0
(-2950 2300);
DISPLAY INVISIBLE (-2950 2300);
FORCEPROP 1 LAST PATH I10
J 0
(-2875 2300);
DISPLAY 0.872340 (-2875 2300);
PAINT AQUA (-2875 2300);
DISPLAY INVISIBLE (-2875 2300);
FORCEADD PICOPROBE_BXA..1
(-2400 1625);
FORCEPROP 1 LAST PART_NUMBER TP33
J 0
(-2550 1778);
DISPLAY 0.723404 (-2550 1778);
PAINT GREEN (-2550 1778);
DISPLAY INVISIBLE (-2550 1778);
FORCEPROP 1 LAST MATERIAL EMPTY
J 0
(-2554 1730);
DISPLAY 0.723404 (-2554 1730);
PAINT GREEN (-2554 1730);
FORCEPROP 2 LAST PART_TYPE SMLF
J 0
(-2546 1921);
DISPLAY 1.021277 (-2546 1921);
FORCEPROP 2 LAST VALUE DELTA-L 4.0
J 0
(-2546 1871);
DISPLAY 1.021277 (-2546 1871);
FORCEPROP 1 LAST LOCATION J67
J 0
(-2550 1825);
DISPLAY 0.723404 (-2550 1825);
PAINT GREEN (-2550 1825);
FORCEPROP 0 LASTPIN (-2100 1625) $PN 1
J 0
(-2090 1635);
DISPLAY 0.680851 (-2090 1635);
PAINT MONO (-2090 1635);
FORCEPROP 0 LASTPIN (-2100 1675) $PN 2
J 0
(-2090 1685);
DISPLAY 0.680851 (-2090 1685);
PAINT MONO (-2090 1685);
FORCEPROP 0 LASTPIN (-2700 1675) $PN 3
J 2
(-2710 1685);
DISPLAY 0.680851 (-2710 1685);
PAINT MONO (-2710 1685);
FORCEPROP 2 LAST CDS_LIB pure_quanta
J 0
(-2400 1625);
DISPLAY INVISIBLE (-2400 1625);
FORCEPROP 1 LAST CDS_LMAN_SYM_OUTLINE -150,100,150,-100
J 0
(-2400 1625);
DISPLAY 0.468085 (-2400 1625);
PAINT GREEN (-2400 1625);
DISPLAY INVISIBLE (-2400 1625);
FORCEPROP 1 LAST NEEDS_NO_SIZE TRUE
J 0
(-2400 1625);
DISPLAY 0.723404 (-2400 1625);
PAINT GREEN (-2400 1625);
DISPLAY INVISIBLE (-2400 1625);
FORCEPROP 1 LAST PATH I11
J 0
(-2400 1625);
DISPLAY 0.723404 (-2400 1625);
PAINT GREEN (-2400 1625);
DISPLAY INVISIBLE (-2400 1625);
FORCEPROP 0 LAST $SEC 1
J 0
(-2525 1975);
DISPLAY 0.680851 (-2525 1975);
PAINT MONO (-2525 1975);
DISPLAY INVISIBLE (-2525 1975);
FORCEPROP 0 LAST CDS_SEC 1
J 0
(-2525 1975);
DISPLAY 1.021277 (-2525 1975);
DISPLAY INVISIBLE (-2525 1975);
FORCEADD PICOPROBE_BXA..1
(-2400 2475);
FORCEPROP 1 LAST PART_NUMBER TP33
J 0
(-2550 2628);
DISPLAY 0.723404 (-2550 2628);
PAINT GREEN (-2550 2628);
DISPLAY INVISIBLE (-2550 2628);
FORCEPROP 2 LAST PART_TYPE SMLF
J 0
(-2546 2771);
DISPLAY 1.021277 (-2546 2771);
FORCEPROP 1 LAST MATERIAL EMPTY
J 0
(-2554 2580);
DISPLAY 0.723404 (-2554 2580);
PAINT GREEN (-2554 2580);
FORCEPROP 2 LAST VALUE DELTA-L 4.0
J 0
(-2546 2721);
DISPLAY 1.021277 (-2546 2721);
FORCEPROP 1 LAST LOCATION J66
J 0
(-2550 2675);
DISPLAY 0.723404 (-2550 2675);
PAINT GREEN (-2550 2675);
FORCEPROP 0 LASTPIN (-2100 2475) $PN 1
J 0
(-2090 2485);
DISPLAY 0.680851 (-2090 2485);
PAINT MONO (-2090 2485);
FORCEPROP 0 LASTPIN (-2100 2525) $PN 2
J 0
(-2090 2535);
DISPLAY 0.680851 (-2090 2535);
PAINT MONO (-2090 2535);
FORCEPROP 0 LASTPIN (-2700 2525) $PN 3
J 2
(-2710 2535);
DISPLAY 0.680851 (-2710 2535);
PAINT MONO (-2710 2535);
FORCEPROP 1 LAST NEEDS_NO_SIZE TRUE
J 0
(-2400 2475);
DISPLAY 0.723404 (-2400 2475);
PAINT GREEN (-2400 2475);
DISPLAY INVISIBLE (-2400 2475);
FORCEPROP 1 LAST CDS_LMAN_SYM_OUTLINE -150,100,150,-100
J 0
(-2400 2475);
DISPLAY 0.468085 (-2400 2475);
PAINT GREEN (-2400 2475);
DISPLAY INVISIBLE (-2400 2475);
FORCEPROP 2 LAST CDS_LIB pure_quanta
J 0
(-2400 2475);
DISPLAY INVISIBLE (-2400 2475);
FORCEPROP 1 LAST PATH I12
J 0
(-2400 2475);
DISPLAY 0.723404 (-2400 2475);
PAINT GREEN (-2400 2475);
DISPLAY INVISIBLE (-2400 2475);
FORCEPROP 0 LAST $SEC 1
J 0
(-2525 2825);
DISPLAY 0.680851 (-2525 2825);
PAINT MONO (-2525 2825);
DISPLAY INVISIBLE (-2525 2825);
FORCEPROP 0 LAST CDS_SEC 1
J 0
(-2525 2825);
DISPLAY 1.021277 (-2525 2825);
DISPLAY INVISIBLE (-2525 2825);
FORCEADD UNIVERSAL_GND..1
(-2950 2875);
FORCEPROP 3 LASTPIN (-2950 2925) SIG_NAME DELTA_L_GND_1\g
J 0
(-2940 2935);
DISPLAY 0.659574 (-2940 2935);
PAINT MONO (-2940 2935);
DISPLAY INVISIBLE (-2940 2935);
FORCEPROP 1 LAST HDL_POWER DELTA_L_GND_1
J 1
(-2925 2800);
DISPLAY 0.872340 (-2925 2800);
PAINT GREEN (-2925 2800);
FORCEPROP 2 LAST CDS_LIB logical_power
J 0
(-2950 2875);
DISPLAY INVISIBLE (-2950 2875);
FORCEPROP 1 LAST PATH I13
J 0
(-2875 2875);
DISPLAY 0.872340 (-2875 2875);
PAINT AQUA (-2875 2875);
DISPLAY INVISIBLE (-2875 2875);
FORCEADD PICOPROBE_BXA..1
(-2400 3050);
FORCEPROP 1 LAST PART_NUMBER TP33
J 0
(-2550 3203);
DISPLAY 0.723404 (-2550 3203);
PAINT GREEN (-2550 3203);
DISPLAY INVISIBLE (-2550 3203);
FORCEPROP 1 LAST MATERIAL EMPTY
J 0
(-2554 3155);
DISPLAY 0.723404 (-2554 3155);
PAINT GREEN (-2554 3155);
FORCEPROP 2 LAST VALUE DELTA-L 4.0
J 0
(-2546 3296);
DISPLAY 1.021277 (-2546 3296);
FORCEPROP 2 LAST PART_TYPE SMLF
J 0
(-2546 3346);
DISPLAY 1.021277 (-2546 3346);
FORCEPROP 1 LAST LOCATION J65
J 0
(-2550 3250);
DISPLAY 0.723404 (-2550 3250);
PAINT GREEN (-2550 3250);
FORCEPROP 0 LASTPIN (-2100 3050) $PN 1
J 0
(-2090 3060);
DISPLAY 0.680851 (-2090 3060);
PAINT MONO (-2090 3060);
FORCEPROP 0 LASTPIN (-2100 3100) $PN 2
J 0
(-2090 3110);
DISPLAY 0.680851 (-2090 3110);
PAINT MONO (-2090 3110);
FORCEPROP 0 LASTPIN (-2700 3100) $PN 3
J 2
(-2710 3110);
DISPLAY 0.680851 (-2710 3110);
PAINT MONO (-2710 3110);
FORCEPROP 1 LAST NEEDS_NO_SIZE TRUE
J 0
(-2400 3050);
DISPLAY 0.723404 (-2400 3050);
PAINT GREEN (-2400 3050);
DISPLAY INVISIBLE (-2400 3050);
FORCEPROP 1 LAST CDS_LMAN_SYM_OUTLINE -150,100,150,-100
J 0
(-2400 3050);
DISPLAY 0.468085 (-2400 3050);
PAINT GREEN (-2400 3050);
DISPLAY INVISIBLE (-2400 3050);
FORCEPROP 2 LAST CDS_LIB pure_quanta
J 0
(-2400 3050);
DISPLAY INVISIBLE (-2400 3050);
FORCEPROP 1 LAST PATH I14
J 0
(-2400 3050);
DISPLAY 0.723404 (-2400 3050);
PAINT GREEN (-2400 3050);
DISPLAY INVISIBLE (-2400 3050);
FORCEPROP 0 LAST $SEC 1
J 0
(-2525 3400);
DISPLAY 0.680851 (-2525 3400);
PAINT MONO (-2525 3400);
DISPLAY INVISIBLE (-2525 3400);
FORCEPROP 0 LAST CDS_SEC 1
J 0
(-2525 3400);
DISPLAY 1.021277 (-2525 3400);
DISPLAY INVISIBLE (-2525 3400);
FORCEADD UNIVERSAL_GND..1
(-2950 3775);
FORCEPROP 3 LASTPIN (-2950 3825) SIG_NAME DELTA_L_GND_1\g
J 0
(-2940 3835);
DISPLAY 0.659574 (-2940 3835);
PAINT MONO (-2940 3835);
DISPLAY INVISIBLE (-2940 3835);
FORCEPROP 1 LAST HDL_POWER DELTA_L_GND_1
J 1
(-2925 3700);
DISPLAY 0.872340 (-2925 3700);
PAINT GREEN (-2925 3700);
FORCEPROP 2 LAST CDS_LIB logical_power
J 0
(-2950 3775);
DISPLAY INVISIBLE (-2950 3775);
FORCEPROP 1 LAST PATH I15
J 0
(-2875 3775);
DISPLAY 0.872340 (-2875 3775);
PAINT AQUA (-2875 3775);
DISPLAY INVISIBLE (-2875 3775);
FORCEADD UNIVERSAL_GND..1
(-2950 4350);
FORCEPROP 3 LASTPIN (-2950 4400) SIG_NAME DELTA_L_GND_1\g
J 0
(-2940 4410);
DISPLAY 0.659574 (-2940 4410);
PAINT MONO (-2940 4410);
DISPLAY INVISIBLE (-2940 4410);
FORCEPROP 1 LAST HDL_POWER DELTA_L_GND_1
J 1
(-2925 4275);
DISPLAY 0.872340 (-2925 4275);
PAINT GREEN (-2925 4275);
FORCEPROP 2 LAST CDS_LIB logical_power
J 0
(-2950 4350);
DISPLAY INVISIBLE (-2950 4350);
FORCEPROP 1 LAST PATH I16
J 0
(-2875 4350);
DISPLAY 0.872340 (-2875 4350);
PAINT AQUA (-2875 4350);
DISPLAY INVISIBLE (-2875 4350);
FORCEADD PICOPROBE_BXA..1
(-2400 3950);
FORCEPROP 1 LAST PART_NUMBER TP33
J 0
(-2550 4103);
DISPLAY 0.723404 (-2550 4103);
PAINT GREEN (-2550 4103);
DISPLAY INVISIBLE (-2550 4103);
FORCEPROP 1 LAST MATERIAL EMPTY
J 0
(-2554 4055);
DISPLAY 0.723404 (-2554 4055);
PAINT GREEN (-2554 4055);
FORCEPROP 2 LAST PART_TYPE SMLF
J 0
(-2546 4246);
DISPLAY 1.021277 (-2546 4246);
FORCEPROP 2 LAST VALUE DELTA-L 4.0
J 0
(-2546 4196);
DISPLAY 1.021277 (-2546 4196);
FORCEPROP 1 LAST LOCATION J64
J 0
(-2550 4150);
DISPLAY 0.723404 (-2550 4150);
PAINT GREEN (-2550 4150);
FORCEPROP 0 LASTPIN (-2100 3950) $PN 1
J 0
(-2090 3960);
DISPLAY 0.680851 (-2090 3960);
PAINT MONO (-2090 3960);
FORCEPROP 0 LASTPIN (-2100 4000) $PN 2
J 0
(-2090 4010);
DISPLAY 0.680851 (-2090 4010);
PAINT MONO (-2090 4010);
FORCEPROP 0 LASTPIN (-2700 4000) $PN 3
J 2
(-2710 4010);
DISPLAY 0.680851 (-2710 4010);
PAINT MONO (-2710 4010);
FORCEPROP 2 LAST CDS_LIB pure_quanta
J 0
(-2400 3950);
DISPLAY INVISIBLE (-2400 3950);
FORCEPROP 1 LAST CDS_LMAN_SYM_OUTLINE -150,100,150,-100
J 0
(-2400 3950);
DISPLAY 0.468085 (-2400 3950);
PAINT GREEN (-2400 3950);
DISPLAY INVISIBLE (-2400 3950);
FORCEPROP 1 LAST NEEDS_NO_SIZE TRUE
J 0
(-2400 3950);
DISPLAY 0.723404 (-2400 3950);
PAINT GREEN (-2400 3950);
DISPLAY INVISIBLE (-2400 3950);
FORCEPROP 1 LAST PATH I17
J 0
(-2400 3950);
DISPLAY 0.723404 (-2400 3950);
PAINT GREEN (-2400 3950);
DISPLAY INVISIBLE (-2400 3950);
FORCEPROP 0 LAST $SEC 1
J 0
(-2525 4300);
DISPLAY 0.680851 (-2525 4300);
PAINT MONO (-2525 4300);
DISPLAY INVISIBLE (-2525 4300);
FORCEPROP 0 LAST CDS_SEC 1
J 0
(-2525 4300);
DISPLAY 1.021277 (-2525 4300);
DISPLAY INVISIBLE (-2525 4300);
FORCEADD PICOPROBE_BXA..1
(-2400 4525);
FORCEPROP 1 LAST PART_NUMBER TP33
J 0
(-2554 4682);
DISPLAY 0.723404 (-2554 4682);
PAINT GREEN (-2554 4682);
DISPLAY INVISIBLE (-2554 4682);
FORCEPROP 1 LAST MATERIAL EMPTY
J 0
(-2554 4630);
DISPLAY 0.723404 (-2554 4630);
PAINT GREEN (-2554 4630);
FORCEPROP 2 LAST PART_TYPE SMLF
J 0
(-2546 4821);
DISPLAY 1.021277 (-2546 4821);
FORCEPROP 2 LAST VALUE DELTA-L 4.0
J 0
(-2546 4771);
DISPLAY 1.021277 (-2546 4771);
FORCEPROP 1 LAST LOCATION J63
J 0
(-2550 4725);
DISPLAY 0.723404 (-2550 4725);
PAINT GREEN (-2550 4725);
FORCEPROP 0 LASTPIN (-2100 4525) $PN 1
J 0
(-2090 4535);
DISPLAY 0.680851 (-2090 4535);
PAINT MONO (-2090 4535);
FORCEPROP 0 LASTPIN (-2100 4575) $PN 2
J 0
(-2090 4585);
DISPLAY 0.680851 (-2090 4585);
PAINT MONO (-2090 4585);
FORCEPROP 0 LASTPIN (-2700 4575) $PN 3
J 2
(-2710 4585);
DISPLAY 0.680851 (-2710 4585);
PAINT MONO (-2710 4585);
FORCEPROP 1 LAST CDS_LMAN_SYM_OUTLINE -150,100,150,-100
J 0
(-2400 4525);
DISPLAY 0.468085 (-2400 4525);
PAINT GREEN (-2400 4525);
DISPLAY INVISIBLE (-2400 4525);
FORCEPROP 1 LAST NEEDS_NO_SIZE TRUE
J 0
(-2400 4525);
DISPLAY 0.723404 (-2400 4525);
PAINT GREEN (-2400 4525);
DISPLAY INVISIBLE (-2400 4525);
FORCEPROP 2 LAST CDS_LIB pure_quanta
J 0
(-2400 4525);
DISPLAY INVISIBLE (-2400 4525);
FORCEPROP 1 LAST PATH I18
J 0
(-2400 4525);
DISPLAY 0.723404 (-2400 4525);
PAINT GREEN (-2400 4525);
DISPLAY INVISIBLE (-2400 4525);
FORCEPROP 0 LAST $SEC 1
J 0
(-2525 4875);
DISPLAY 0.680851 (-2525 4875);
PAINT MONO (-2525 4875);
DISPLAY INVISIBLE (-2525 4875);
FORCEPROP 0 LAST CDS_SEC 1
J 0
(-2525 4875);
DISPLAY 1.021277 (-2525 4875);
DISPLAY INVISIBLE (-2525 4875);
FORCEADD PICOPROBE_BXA..1
R 4
(-350 1100);
FORCEPROP 1 LAST PART_NUMBER TP33
R 2
J 0
(-196 943);
DISPLAY 0.723404 (-196 943);
PAINT GREEN (-196 943);
DISPLAY INVISIBLE (-196 943);
FORCEPROP 2 LAST VALUE DELTA-L 4.0
R 2
J 0
(-200 900);
DISPLAY 1.021277 (-200 900);
FORCEPROP 2 LAST PART_TYPE SMLF
R 2
J 0
(-200 850);
DISPLAY 1.021277 (-200 850);
FORCEPROP 1 LAST MATERIAL EMPTY
R 2
J 0
(-196 995);
DISPLAY 0.723404 (-196 995);
PAINT GREEN (-196 995);
FORCEPROP 1 LAST LOCATION J74
R 2
J 0
(-196 721);
DISPLAY 0.723404 (-196 721);
PAINT GREEN (-196 721);
FORCEPROP 0 LASTPIN (-650 1100) $PN 1
J 2
(-660 1090);
DISPLAY 0.680851 (-660 1090);
PAINT MONO (-660 1090);
FORCEPROP 0 LASTPIN (-650 1050) $PN 2
J 2
(-660 1040);
DISPLAY 0.680851 (-660 1040);
PAINT MONO (-660 1040);
FORCEPROP 0 LASTPIN (-50 1050) $PN 3
J 0
(-40 1040);
DISPLAY 0.680851 (-40 1040);
PAINT MONO (-40 1040);
FORCEPROP 2 LAST CDS_LIB pure_quanta
R 2
J 2
(-350 1100);
DISPLAY INVISIBLE (-350 1100);
FORCEPROP 1 LAST CDS_LMAN_SYM_OUTLINE -150,100,150,-100
R 2
J 0
(-350 1100);
DISPLAY 0.468085 (-350 1100);
PAINT GREEN (-350 1100);
DISPLAY INVISIBLE (-350 1100);
FORCEPROP 1 LAST NEEDS_NO_SIZE TRUE
R 2
J 0
(-350 1100);
DISPLAY 0.723404 (-350 1100);
PAINT GREEN (-350 1100);
DISPLAY INVISIBLE (-350 1100);
FORCEPROP 1 LAST PATH I19
R 2
J 0
(-350 1100);
DISPLAY 0.723404 (-350 1100);
PAINT GREEN (-350 1100);
DISPLAY INVISIBLE (-350 1100);
FORCEPROP 0 LAST $SEC 1
R 2
J 2
(-175 675);
DISPLAY 0.680851 (-175 675);
PAINT MONO (-175 675);
DISPLAY INVISIBLE (-175 675);
FORCEPROP 0 LAST CDS_SEC 1
R 2
J 2
(-175 675);
DISPLAY 1.021277 (-175 675);
DISPLAY INVISIBLE (-175 675);
FORCEADD UNIVERSAL_GND..1
(-2900 50);
FORCEPROP 3 LASTPIN (-2900 100) SIG_NAME DELTA_L_GND_1\g
J 0
(-2890 110);
DISPLAY 0.659574 (-2890 110);
PAINT MONO (-2890 110);
DISPLAY INVISIBLE (-2890 110);
FORCEPROP 1 LAST HDL_POWER DELTA_L_GND_1
J 1
(-2875 -25);
DISPLAY 0.872340 (-2875 -25);
PAINT GREEN (-2875 -25);
FORCEPROP 2 LAST CDS_LIB logical_power
J 0
(-2900 50);
DISPLAY INVISIBLE (-2900 50);
FORCEPROP 1 LAST PATH I2
J 0
(-2825 50);
DISPLAY 0.872340 (-2825 50);
PAINT AQUA (-2825 50);
DISPLAY INVISIBLE (-2825 50);
FORCEADD PICOPROBE_BXA..1
R 4
(-350 1675);
FORCEPROP 1 LAST PART_NUMBER TP33
R 2
J 0
(-196 1518);
DISPLAY 0.723404 (-196 1518);
PAINT GREEN (-196 1518);
DISPLAY INVISIBLE (-196 1518);
FORCEPROP 1 LAST MATERIAL EMPTY
R 2
J 0
(-196 1570);
DISPLAY 0.723404 (-196 1570);
PAINT GREEN (-196 1570);
FORCEPROP 2 LAST VALUE DELTA-L 4.0
R 2
J 0
(-200 1475);
DISPLAY 1.021277 (-200 1475);
FORCEPROP 2 LAST PART_TYPE SMLF
R 2
J 0
(-200 1425);
DISPLAY 1.021277 (-200 1425);
FORCEPROP 1 LAST LOCATION J73
R 2
J 0
(-196 1296);
DISPLAY 0.723404 (-196 1296);
PAINT GREEN (-196 1296);
FORCEPROP 0 LASTPIN (-650 1675) $PN 1
J 2
(-660 1665);
DISPLAY 0.680851 (-660 1665);
PAINT MONO (-660 1665);
FORCEPROP 0 LASTPIN (-650 1625) $PN 2
J 2
(-660 1615);
DISPLAY 0.680851 (-660 1615);
PAINT MONO (-660 1615);
FORCEPROP 0 LASTPIN (-50 1625) $PN 3
J 0
(-40 1615);
DISPLAY 0.680851 (-40 1615);
PAINT MONO (-40 1615);
FORCEPROP 2 LAST CDS_LIB pure_quanta
R 2
J 2
(-350 1675);
DISPLAY INVISIBLE (-350 1675);
FORCEPROP 1 LAST CDS_LMAN_SYM_OUTLINE -150,100,150,-100
R 2
J 0
(-350 1675);
DISPLAY 0.468085 (-350 1675);
PAINT GREEN (-350 1675);
DISPLAY INVISIBLE (-350 1675);
FORCEPROP 1 LAST NEEDS_NO_SIZE TRUE
R 2
J 0
(-350 1675);
DISPLAY 0.723404 (-350 1675);
PAINT GREEN (-350 1675);
DISPLAY INVISIBLE (-350 1675);
FORCEPROP 1 LAST PATH I20
R 2
J 0
(-350 1675);
DISPLAY 0.723404 (-350 1675);
PAINT GREEN (-350 1675);
DISPLAY INVISIBLE (-350 1675);
FORCEPROP 0 LAST $SEC 1
R 2
J 2
(-175 1250);
DISPLAY 0.680851 (-175 1250);
PAINT MONO (-175 1250);
DISPLAY INVISIBLE (-175 1250);
FORCEPROP 0 LAST CDS_SEC 1
R 2
J 2
(-175 1250);
DISPLAY 1.021277 (-175 1250);
DISPLAY INVISIBLE (-175 1250);
FORCEADD PICOPROBE_BXA..1
R 4
(-350 2525);
FORCEPROP 1 LAST PART_NUMBER TP33
R 2
J 0
(-196 2368);
DISPLAY 0.723404 (-196 2368);
PAINT GREEN (-196 2368);
DISPLAY INVISIBLE (-196 2368);
FORCEPROP 2 LAST VALUE DELTA-L 4.0
R 2
J 0
(-200 2325);
DISPLAY 1.021277 (-200 2325);
FORCEPROP 2 LAST PART_TYPE SMLF
R 2
J 0
(-200 2275);
DISPLAY 1.021277 (-200 2275);
FORCEPROP 1 LAST MATERIAL EMPTY
R 2
J 0
(-196 2420);
DISPLAY 0.723404 (-196 2420);
PAINT GREEN (-196 2420);
FORCEPROP 1 LAST LOCATION J72
R 2
J 0
(-196 2146);
DISPLAY 0.723404 (-196 2146);
PAINT GREEN (-196 2146);
FORCEPROP 0 LASTPIN (-650 2525) $PN 1
J 2
(-660 2515);
DISPLAY 0.680851 (-660 2515);
PAINT MONO (-660 2515);
FORCEPROP 0 LASTPIN (-650 2475) $PN 2
J 2
(-660 2465);
DISPLAY 0.680851 (-660 2465);
PAINT MONO (-660 2465);
FORCEPROP 0 LASTPIN (-50 2475) $PN 3
J 0
(-40 2465);
DISPLAY 0.680851 (-40 2465);
PAINT MONO (-40 2465);
FORCEPROP 1 LAST NEEDS_NO_SIZE TRUE
R 2
J 0
(-350 2525);
DISPLAY 0.723404 (-350 2525);
PAINT GREEN (-350 2525);
DISPLAY INVISIBLE (-350 2525);
FORCEPROP 1 LAST CDS_LMAN_SYM_OUTLINE -150,100,150,-100
R 2
J 0
(-350 2525);
DISPLAY 0.468085 (-350 2525);
PAINT GREEN (-350 2525);
DISPLAY INVISIBLE (-350 2525);
FORCEPROP 2 LAST CDS_LIB pure_quanta
R 2
J 2
(-350 2525);
DISPLAY INVISIBLE (-350 2525);
FORCEPROP 1 LAST PATH I21
R 2
J 0
(-350 2525);
DISPLAY 0.723404 (-350 2525);
PAINT GREEN (-350 2525);
DISPLAY INVISIBLE (-350 2525);
FORCEPROP 0 LAST $SEC 1
R 2
J 2
(-175 2100);
DISPLAY 0.680851 (-175 2100);
PAINT MONO (-175 2100);
DISPLAY INVISIBLE (-175 2100);
FORCEPROP 0 LAST CDS_SEC 1
R 2
J 2
(-175 2100);
DISPLAY 1.021277 (-175 2100);
DISPLAY INVISIBLE (-175 2100);
FORCEADD PICOPROBE_BXA..1
R 4
(-350 3100);
FORCEPROP 1 LAST PART_NUMBER TP33
R 2
J 0
(-196 2943);
DISPLAY 0.723404 (-196 2943);
PAINT GREEN (-196 2943);
DISPLAY INVISIBLE (-196 2943);
FORCEPROP 1 LAST MATERIAL EMPTY
R 2
J 0
(-196 2995);
DISPLAY 0.723404 (-196 2995);
PAINT GREEN (-196 2995);
FORCEPROP 2 LAST VALUE DELTA-L 4.0
R 2
J 0
(-200 2900);
DISPLAY 1.021277 (-200 2900);
FORCEPROP 2 LAST PART_TYPE SMLF
R 2
J 0
(-200 2850);
DISPLAY 1.021277 (-200 2850);
FORCEPROP 1 LAST LOCATION J71
R 2
J 0
(-196 2721);
DISPLAY 0.723404 (-196 2721);
PAINT GREEN (-196 2721);
FORCEPROP 0 LASTPIN (-650 3100) $PN 1
J 2
(-660 3090);
DISPLAY 0.680851 (-660 3090);
PAINT MONO (-660 3090);
FORCEPROP 0 LASTPIN (-650 3050) $PN 2
J 2
(-660 3040);
DISPLAY 0.680851 (-660 3040);
PAINT MONO (-660 3040);
FORCEPROP 0 LASTPIN (-50 3050) $PN 3
J 0
(-40 3040);
DISPLAY 0.680851 (-40 3040);
PAINT MONO (-40 3040);
FORCEPROP 1 LAST NEEDS_NO_SIZE TRUE
R 2
J 0
(-350 3100);
DISPLAY 0.723404 (-350 3100);
PAINT GREEN (-350 3100);
DISPLAY INVISIBLE (-350 3100);
FORCEPROP 1 LAST CDS_LMAN_SYM_OUTLINE -150,100,150,-100
R 2
J 0
(-350 3100);
DISPLAY 0.468085 (-350 3100);
PAINT GREEN (-350 3100);
DISPLAY INVISIBLE (-350 3100);
FORCEPROP 2 LAST CDS_LIB pure_quanta
R 2
J 2
(-350 3100);
DISPLAY INVISIBLE (-350 3100);
FORCEPROP 1 LAST PATH I22
R 2
J 0
(-350 3100);
DISPLAY 0.723404 (-350 3100);
PAINT GREEN (-350 3100);
DISPLAY INVISIBLE (-350 3100);
FORCEPROP 0 LAST $SEC 1
R 2
J 2
(-175 2675);
DISPLAY 0.680851 (-175 2675);
PAINT MONO (-175 2675);
DISPLAY INVISIBLE (-175 2675);
FORCEPROP 0 LAST CDS_SEC 1
R 2
J 2
(-175 2675);
DISPLAY 1.021277 (-175 2675);
DISPLAY INVISIBLE (-175 2675);
FORCEADD PICOPROBE_BXA..1
R 4
(-350 4000);
FORCEPROP 1 LAST PART_NUMBER TP33
R 2
J 0
(-196 3843);
DISPLAY 0.723404 (-196 3843);
PAINT GREEN (-196 3843);
DISPLAY INVISIBLE (-196 3843);
FORCEPROP 2 LAST VALUE DELTA-L 4.0
R 2
J 0
(-200 3800);
DISPLAY 1.021277 (-200 3800);
FORCEPROP 1 LAST MATERIAL EMPTY
R 2
J 0
(-196 3895);
DISPLAY 0.723404 (-196 3895);
PAINT GREEN (-196 3895);
FORCEPROP 2 LAST PART_TYPE SMLF
R 2
J 0
(-200 3750);
DISPLAY 1.021277 (-200 3750);
FORCEPROP 1 LAST LOCATION J70
R 2
J 0
(-192 3667);
DISPLAY 0.723404 (-192 3667);
PAINT GREEN (-192 3667);
FORCEPROP 0 LASTPIN (-650 4000) $PN 1
J 2
(-660 3990);
DISPLAY 0.680851 (-660 3990);
PAINT MONO (-660 3990);
FORCEPROP 0 LASTPIN (-650 3950) $PN 2
J 2
(-660 3940);
DISPLAY 0.680851 (-660 3940);
PAINT MONO (-660 3940);
FORCEPROP 0 LASTPIN (-50 3950) $PN 3
J 0
(-40 3940);
DISPLAY 0.680851 (-40 3940);
PAINT MONO (-40 3940);
FORCEPROP 1 LAST NEEDS_NO_SIZE TRUE
R 2
J 0
(-350 4000);
DISPLAY 0.723404 (-350 4000);
PAINT GREEN (-350 4000);
DISPLAY INVISIBLE (-350 4000);
FORCEPROP 1 LAST CDS_LMAN_SYM_OUTLINE -150,100,150,-100
R 2
J 0
(-350 4000);
DISPLAY 0.468085 (-350 4000);
PAINT GREEN (-350 4000);
DISPLAY INVISIBLE (-350 4000);
FORCEPROP 2 LAST CDS_LIB pure_quanta
R 2
J 0
(-350 4000);
DISPLAY INVISIBLE (-350 4000);
FORCEPROP 1 LAST PATH I23
R 2
J 0
(-350 4000);
DISPLAY 0.723404 (-350 4000);
PAINT GREEN (-350 4000);
DISPLAY INVISIBLE (-350 4000);
FORCEPROP 0 LAST $SEC 1
R 2
J 2
(-175 3625);
DISPLAY 0.680851 (-175 3625);
PAINT MONO (-175 3625);
DISPLAY INVISIBLE (-175 3625);
FORCEPROP 0 LAST CDS_SEC 1
R 2
J 2
(-175 3625);
DISPLAY 1.021277 (-175 3625);
DISPLAY INVISIBLE (-175 3625);
FORCEADD PICOPROBE_BXA..1
R 4
(-325 4575);
FORCEPROP 1 LAST PART_NUMBER TP33
R 2
J 0
(-171 4418);
DISPLAY 0.723404 (-171 4418);
PAINT GREEN (-171 4418);
DISPLAY INVISIBLE (-171 4418);
FORCEPROP 1 LAST MATERIAL EMPTY
R 2
J 0
(-171 4470);
DISPLAY 0.723404 (-171 4470);
PAINT GREEN (-171 4470);
FORCEPROP 2 LAST PART_TYPE SMLF
R 2
J 0
(-175 4325);
DISPLAY 1.021277 (-175 4325);
FORCEPROP 2 LAST VALUE DELTA-L 4.0
R 2
J 0
(-175 4375);
DISPLAY 1.021277 (-175 4375);
FORCEPROP 1 LAST LOCATION J69
R 2
J 0
(-167 4242);
DISPLAY 0.723404 (-167 4242);
PAINT GREEN (-167 4242);
FORCEPROP 0 LASTPIN (-625 4575) $PN 1
J 2
(-635 4565);
DISPLAY 0.680851 (-635 4565);
PAINT MONO (-635 4565);
FORCEPROP 0 LASTPIN (-625 4525) $PN 2
J 2
(-635 4515);
DISPLAY 0.680851 (-635 4515);
PAINT MONO (-635 4515);
FORCEPROP 0 LASTPIN (-25 4525) $PN 3
J 0
(-15 4515);
DISPLAY 0.680851 (-15 4515);
PAINT MONO (-15 4515);
FORCEPROP 1 LAST NEEDS_NO_SIZE TRUE
R 2
J 0
(-325 4575);
DISPLAY 0.723404 (-325 4575);
PAINT GREEN (-325 4575);
DISPLAY INVISIBLE (-325 4575);
FORCEPROP 1 LAST CDS_LMAN_SYM_OUTLINE -150,100,150,-100
R 2
J 0
(-325 4575);
DISPLAY 0.468085 (-325 4575);
PAINT GREEN (-325 4575);
DISPLAY INVISIBLE (-325 4575);
FORCEPROP 2 LAST CDS_LIB pure_quanta
R 2
J 0
(-325 4575);
DISPLAY INVISIBLE (-325 4575);
FORCEPROP 1 LAST PATH I24
R 2
J 0
(-325 4575);
DISPLAY 0.723404 (-325 4575);
PAINT GREEN (-325 4575);
DISPLAY INVISIBLE (-325 4575);
FORCEPROP 0 LAST $SEC 1
R 2
J 2
(-150 4200);
DISPLAY 0.680851 (-150 4200);
PAINT MONO (-150 4200);
DISPLAY INVISIBLE (-150 4200);
FORCEPROP 0 LAST CDS_SEC 1
R 2
J 2
(-150 4200);
DISPLAY 1.021277 (-150 4200);
DISPLAY INVISIBLE (-150 4200);
FORCEADD UNIVERSAL_GND..1
(250 -475);
FORCEPROP 3 LASTPIN (250 -425) SIG_NAME DELTA_L_GND_1\g
J 0
(260 -415);
DISPLAY 0.659574 (260 -415);
PAINT MONO (260 -415);
DISPLAY INVISIBLE (260 -415);
FORCEPROP 1 LAST HDL_POWER DELTA_L_GND_1
J 1
(275 -550);
DISPLAY 0.872340 (275 -550);
PAINT GREEN (275 -550);
FORCEPROP 2 LAST CDS_LIB logical_power
J 0
(250 -475);
DISPLAY INVISIBLE (250 -475);
FORCEPROP 1 LAST PATH I25
J 0
(325 -475);
DISPLAY 0.872340 (325 -475);
PAINT AQUA (325 -475);
DISPLAY INVISIBLE (325 -475);
FORCEADD UNIVERSAL_GND..1
(250 100);
FORCEPROP 3 LASTPIN (250 150) SIG_NAME DELTA_L_GND_1\g
J 0
(260 160);
DISPLAY 0.659574 (260 160);
PAINT MONO (260 160);
DISPLAY INVISIBLE (260 160);
FORCEPROP 1 LAST HDL_POWER DELTA_L_GND_1
J 1
(275 25);
DISPLAY 0.872340 (275 25);
PAINT GREEN (275 25);
FORCEPROP 2 LAST CDS_LIB logical_power
J 0
(250 100);
DISPLAY INVISIBLE (250 100);
FORCEPROP 1 LAST PATH I26
J 0
(325 100);
DISPLAY 0.872340 (325 100);
PAINT AQUA (325 100);
DISPLAY INVISIBLE (325 100);
FORCEADD UNIVERSAL_GND..1
(1300 -500);
FORCEPROP 3 LASTPIN (1300 -450) SIG_NAME DELTA_L_GND_1\g
J 0
(1310 -440);
DISPLAY 0.659574 (1310 -440);
PAINT MONO (1310 -440);
DISPLAY INVISIBLE (1310 -440);
FORCEPROP 1 LAST HDL_POWER DELTA_L_GND_1
J 1
(1325 -575);
DISPLAY 0.872340 (1325 -575);
PAINT GREEN (1325 -575);
FORCEPROP 2 LAST CDS_LIB logical_power
J 0
(1300 -500);
DISPLAY INVISIBLE (1300 -500);
FORCEPROP 1 LAST PATH I27
J 0
(1375 -500);
DISPLAY 0.872340 (1375 -500);
PAINT AQUA (1375 -500);
DISPLAY INVISIBLE (1375 -500);
FORCEADD PICOPROBE_BXA..1
(1850 -325);
FORCEPROP 1 LAST PART_NUMBER TP33
J 0
(1700 -172);
DISPLAY 0.723404 (1700 -172);
PAINT GREEN (1700 -172);
DISPLAY INVISIBLE (1700 -172);
FORCEPROP 1 LAST MATERIAL EMPTY
J 0
(1696 -220);
DISPLAY 0.723404 (1696 -220);
PAINT GREEN (1696 -220);
FORCEPROP 2 LAST PART_TYPE SMLF
J 0
(1704 -29);
DISPLAY 1.021277 (1704 -29);
FORCEPROP 2 LAST VALUE DELTA-L 4.0
J 0
(1704 -79);
DISPLAY 1.021277 (1704 -79);
FORCEPROP 1 LAST LOCATION J119
J 0
(1700 -125);
DISPLAY 0.723404 (1700 -125);
PAINT GREEN (1700 -125);
FORCEPROP 0 LASTPIN (2150 -325) $PN 1
J 0
(2160 -315);
DISPLAY 0.680851 (2160 -315);
PAINT MONO (2160 -315);
FORCEPROP 0 LASTPIN (2150 -275) $PN 2
J 0
(2160 -265);
DISPLAY 0.680851 (2160 -265);
PAINT MONO (2160 -265);
FORCEPROP 0 LASTPIN (1550 -275) $PN 3
J 2
(1540 -265);
DISPLAY 0.680851 (1540 -265);
PAINT MONO (1540 -265);
FORCEPROP 1 LAST NEEDS_NO_SIZE TRUE
J 0
(1850 -325);
DISPLAY 0.723404 (1850 -325);
PAINT GREEN (1850 -325);
DISPLAY INVISIBLE (1850 -325);
FORCEPROP 1 LAST CDS_LMAN_SYM_OUTLINE -150,100,150,-100
J 0
(1850 -325);
DISPLAY 0.468085 (1850 -325);
PAINT GREEN (1850 -325);
DISPLAY INVISIBLE (1850 -325);
FORCEPROP 2 LAST CDS_LIB pure_quanta
J 0
(1850 -325);
DISPLAY INVISIBLE (1850 -325);
FORCEPROP 1 LAST PATH I28
J 0
(1850 -325);
DISPLAY 0.723404 (1850 -325);
PAINT GREEN (1850 -325);
DISPLAY INVISIBLE (1850 -325);
FORCEPROP 0 LAST $SEC 1
J 0
(1725 25);
DISPLAY 0.680851 (1725 25);
PAINT MONO (1725 25);
DISPLAY INVISIBLE (1725 25);
FORCEPROP 0 LAST CDS_SEC 1
J 0
(1725 25);
DISPLAY 1.021277 (1725 25);
DISPLAY INVISIBLE (1725 25);
FORCEADD UNIVERSAL_GND..1
(1300 75);
FORCEPROP 3 LASTPIN (1300 125) SIG_NAME DELTA_L_GND_1\g
J 0
(1310 135);
DISPLAY 0.659574 (1310 135);
PAINT MONO (1310 135);
DISPLAY INVISIBLE (1310 135);
FORCEPROP 1 LAST HDL_POWER DELTA_L_GND_1
J 1
(1325 0);
DISPLAY 0.872340 (1325 0);
PAINT GREEN (1325 0);
FORCEPROP 2 LAST CDS_LIB logical_power
J 0
(1300 75);
DISPLAY INVISIBLE (1300 75);
FORCEPROP 1 LAST PATH I29
J 0
(1375 75);
DISPLAY 0.872340 (1375 75);
PAINT AQUA (1375 75);
DISPLAY INVISIBLE (1375 75);
FORCEADD PICOPROBE_BXA..1
(-2350 -350);
FORCEPROP 1 LAST PART_NUMBER TP33
J 0
(-2500 -197);
DISPLAY 0.723404 (-2500 -197);
PAINT GREEN (-2500 -197);
DISPLAY INVISIBLE (-2500 -197);
FORCEPROP 1 LAST MATERIAL EMPTY
J 0
(-2504 -245);
DISPLAY 0.723404 (-2504 -245);
PAINT GREEN (-2504 -245);
FORCEPROP 2 LAST PART_TYPE SMLF
J 0
(-2496 -54);
DISPLAY 1.021277 (-2496 -54);
FORCEPROP 2 LAST VALUE DELTA-L 4.0
J 0
(-2496 -104);
DISPLAY 1.021277 (-2496 -104);
FORCEPROP 1 LAST LOCATION J115
J 0
(-2500 -150);
DISPLAY 0.723404 (-2500 -150);
PAINT GREEN (-2500 -150);
FORCEPROP 0 LASTPIN (-2050 -350) $PN 1
J 0
(-2040 -340);
DISPLAY 0.680851 (-2040 -340);
PAINT MONO (-2040 -340);
FORCEPROP 0 LASTPIN (-2050 -300) $PN 2
J 0
(-2040 -290);
DISPLAY 0.680851 (-2040 -290);
PAINT MONO (-2040 -290);
FORCEPROP 0 LASTPIN (-2650 -300) $PN 3
J 2
(-2660 -290);
DISPLAY 0.680851 (-2660 -290);
PAINT MONO (-2660 -290);
FORCEPROP 2 LAST CDS_LIB pure_quanta
J 0
(-2350 -350);
DISPLAY INVISIBLE (-2350 -350);
FORCEPROP 1 LAST CDS_LMAN_SYM_OUTLINE -150,100,150,-100
J 0
(-2350 -350);
DISPLAY 0.468085 (-2350 -350);
PAINT GREEN (-2350 -350);
DISPLAY INVISIBLE (-2350 -350);
FORCEPROP 1 LAST NEEDS_NO_SIZE TRUE
J 0
(-2350 -350);
DISPLAY 0.723404 (-2350 -350);
PAINT GREEN (-2350 -350);
DISPLAY INVISIBLE (-2350 -350);
FORCEPROP 1 LAST PATH I3
J 0
(-2350 -350);
DISPLAY 0.723404 (-2350 -350);
PAINT GREEN (-2350 -350);
DISPLAY INVISIBLE (-2350 -350);
FORCEPROP 0 LAST $SEC 1
J 0
(-2475 0);
DISPLAY 0.680851 (-2475 0);
PAINT MONO (-2475 0);
DISPLAY INVISIBLE (-2475 0);
FORCEPROP 0 LAST CDS_SEC 1
J 0
(-2475 0);
DISPLAY 1.021277 (-2475 0);
DISPLAY INVISIBLE (-2475 0);
FORCEADD PICOPROBE_BXA..1
(1850 250);
FORCEPROP 1 LAST PART_NUMBER TP33
J 0
(1700 403);
DISPLAY 0.723404 (1700 403);
PAINT GREEN (1700 403);
DISPLAY INVISIBLE (1700 403);
FORCEPROP 2 LAST PART_TYPE SMLF
J 0
(1704 546);
DISPLAY 1.021277 (1704 546);
FORCEPROP 1 LAST MATERIAL EMPTY
J 0
(1696 355);
DISPLAY 0.723404 (1696 355);
PAINT GREEN (1696 355);
FORCEPROP 2 LAST VALUE DELTA-L 4.0
J 0
(1704 496);
DISPLAY 1.021277 (1704 496);
FORCEPROP 1 LAST LOCATION J118
J 0
(1700 450);
DISPLAY 0.723404 (1700 450);
PAINT GREEN (1700 450);
FORCEPROP 0 LASTPIN (2150 250) $PN 1
J 0
(2160 260);
DISPLAY 0.680851 (2160 260);
PAINT MONO (2160 260);
FORCEPROP 0 LASTPIN (2150 300) $PN 2
J 0
(2160 310);
DISPLAY 0.680851 (2160 310);
PAINT MONO (2160 310);
FORCEPROP 0 LASTPIN (1550 300) $PN 3
J 2
(1540 310);
DISPLAY 0.680851 (1540 310);
PAINT MONO (1540 310);
FORCEPROP 1 LAST NEEDS_NO_SIZE TRUE
J 0
(1850 250);
DISPLAY 0.723404 (1850 250);
PAINT GREEN (1850 250);
DISPLAY INVISIBLE (1850 250);
FORCEPROP 1 LAST CDS_LMAN_SYM_OUTLINE -150,100,150,-100
J 0
(1850 250);
DISPLAY 0.468085 (1850 250);
PAINT GREEN (1850 250);
DISPLAY INVISIBLE (1850 250);
FORCEPROP 2 LAST CDS_LIB pure_quanta
J 0
(1850 250);
DISPLAY INVISIBLE (1850 250);
FORCEPROP 1 LAST PATH I30
J 0
(1850 250);
DISPLAY 0.723404 (1850 250);
PAINT GREEN (1850 250);
DISPLAY INVISIBLE (1850 250);
FORCEPROP 0 LAST $SEC 1
J 0
(1725 600);
DISPLAY 0.680851 (1725 600);
PAINT MONO (1725 600);
DISPLAY INVISIBLE (1725 600);
FORCEPROP 0 LAST CDS_SEC 1
J 0
(1725 600);
DISPLAY 1.021277 (1725 600);
DISPLAY INVISIBLE (1725 600);
FORCEADD PICOPROBE_BXA..1
R 4
(3900 -275);
FORCEPROP 1 LAST PART_NUMBER TP33
R 2
J 0
(4054 -432);
DISPLAY 0.723404 (4054 -432);
PAINT GREEN (4054 -432);
DISPLAY INVISIBLE (4054 -432);
FORCEPROP 2 LAST VALUE DELTA-L 4.0
R 2
J 0
(4050 -475);
DISPLAY 1.021277 (4050 -475);
FORCEPROP 2 LAST PART_TYPE SMLF
R 2
J 0
(4050 -525);
DISPLAY 1.021277 (4050 -525);
FORCEPROP 1 LAST MATERIAL EMPTY
R 2
J 0
(4054 -380);
DISPLAY 0.723404 (4054 -380);
PAINT GREEN (4054 -380);
FORCEPROP 1 LAST LOCATION J121
R 2
J 0
(4054 -654);
DISPLAY 0.723404 (4054 -654);
PAINT GREEN (4054 -654);
FORCEPROP 0 LASTPIN (3600 -275) $PN 1
J 2
(3590 -285);
DISPLAY 0.680851 (3590 -285);
PAINT MONO (3590 -285);
FORCEPROP 0 LASTPIN (3600 -325) $PN 2
J 2
(3590 -335);
DISPLAY 0.680851 (3590 -335);
PAINT MONO (3590 -335);
FORCEPROP 0 LASTPIN (4200 -325) $PN 3
J 0
(4210 -335);
DISPLAY 0.680851 (4210 -335);
PAINT MONO (4210 -335);
FORCEPROP 2 LAST CDS_LIB pure_quanta
R 2
J 2
(3900 -275);
DISPLAY INVISIBLE (3900 -275);
FORCEPROP 1 LAST CDS_LMAN_SYM_OUTLINE -150,100,150,-100
R 2
J 0
(3900 -275);
DISPLAY 0.468085 (3900 -275);
PAINT GREEN (3900 -275);
DISPLAY INVISIBLE (3900 -275);
FORCEPROP 1 LAST NEEDS_NO_SIZE TRUE
R 2
J 0
(3900 -275);
DISPLAY 0.723404 (3900 -275);
PAINT GREEN (3900 -275);
DISPLAY INVISIBLE (3900 -275);
FORCEPROP 1 LAST PATH I31
R 2
J 0
(3900 -275);
DISPLAY 0.723404 (3900 -275);
PAINT GREEN (3900 -275);
DISPLAY INVISIBLE (3900 -275);
FORCEPROP 0 LAST $SEC 1
R 2
J 2
(4075 -700);
DISPLAY 0.680851 (4075 -700);
PAINT MONO (4075 -700);
DISPLAY INVISIBLE (4075 -700);
FORCEPROP 0 LAST CDS_SEC 1
R 2
J 2
(4075 -700);
DISPLAY 1.021277 (4075 -700);
DISPLAY INVISIBLE (4075 -700);
FORCEADD PICOPROBE_BXA..1
R 4
(3900 300);
FORCEPROP 1 LAST PART_NUMBER TP33
R 2
J 0
(4054 143);
DISPLAY 0.723404 (4054 143);
PAINT GREEN (4054 143);
DISPLAY INVISIBLE (4054 143);
FORCEPROP 2 LAST VALUE DELTA-L 4.0
R 2
J 0
(4050 100);
DISPLAY 1.021277 (4050 100);
FORCEPROP 2 LAST PART_TYPE SMLF
R 2
J 0
(4050 50);
DISPLAY 1.021277 (4050 50);
FORCEPROP 1 LAST MATERIAL EMPTY
R 2
J 0
(4054 195);
DISPLAY 0.723404 (4054 195);
PAINT GREEN (4054 195);
FORCEPROP 1 LAST LOCATION J120
R 2
J 0
(4054 -79);
DISPLAY 0.723404 (4054 -79);
PAINT GREEN (4054 -79);
FORCEPROP 0 LASTPIN (3600 300) $PN 1
J 2
(3590 290);
DISPLAY 0.680851 (3590 290);
PAINT MONO (3590 290);
FORCEPROP 0 LASTPIN (3600 250) $PN 2
J 2
(3590 240);
DISPLAY 0.680851 (3590 240);
PAINT MONO (3590 240);
FORCEPROP 0 LASTPIN (4200 250) $PN 3
J 0
(4210 240);
DISPLAY 0.680851 (4210 240);
PAINT MONO (4210 240);
FORCEPROP 2 LAST CDS_LIB pure_quanta
R 2
J 2
(3900 300);
DISPLAY INVISIBLE (3900 300);
FORCEPROP 1 LAST CDS_LMAN_SYM_OUTLINE -150,100,150,-100
R 2
J 0
(3900 300);
DISPLAY 0.468085 (3900 300);
PAINT GREEN (3900 300);
DISPLAY INVISIBLE (3900 300);
FORCEPROP 1 LAST NEEDS_NO_SIZE TRUE
R 2
J 0
(3900 300);
DISPLAY 0.723404 (3900 300);
PAINT GREEN (3900 300);
DISPLAY INVISIBLE (3900 300);
FORCEPROP 1 LAST PATH I32
R 2
J 0
(3900 300);
DISPLAY 0.723404 (3900 300);
PAINT GREEN (3900 300);
DISPLAY INVISIBLE (3900 300);
FORCEPROP 0 LAST $SEC 1
R 2
J 2
(4075 -125);
DISPLAY 0.680851 (4075 -125);
PAINT MONO (4075 -125);
DISPLAY INVISIBLE (4075 -125);
FORCEPROP 0 LAST CDS_SEC 1
R 2
J 2
(4075 -125);
DISPLAY 1.021277 (4075 -125);
DISPLAY INVISIBLE (4075 -125);
FORCEADD UNIVERSAL_GND..1
(4450 -450);
FORCEPROP 3 LASTPIN (4450 -400) SIG_NAME DELTA_L_GND_1\g
J 0
(4460 -390);
DISPLAY 0.659574 (4460 -390);
PAINT MONO (4460 -390);
DISPLAY INVISIBLE (4460 -390);
FORCEPROP 1 LAST HDL_POWER DELTA_L_GND_1
J 1
(4475 -525);
DISPLAY 0.872340 (4475 -525);
PAINT GREEN (4475 -525);
FORCEPROP 2 LAST CDS_LIB logical_power
J 0
(4450 -450);
DISPLAY INVISIBLE (4450 -450);
FORCEPROP 1 LAST PATH I33
J 0
(4525 -450);
DISPLAY 0.872340 (4525 -450);
PAINT AQUA (4525 -450);
DISPLAY INVISIBLE (4525 -450);
FORCEADD UNIVERSAL_GND..1
(4450 125);
FORCEPROP 3 LASTPIN (4450 175) SIG_NAME DELTA_L_GND_1\g
J 0
(4460 185);
DISPLAY 0.659574 (4460 185);
PAINT MONO (4460 185);
DISPLAY INVISIBLE (4460 185);
FORCEPROP 1 LAST HDL_POWER DELTA_L_GND_1
J 1
(4475 50);
DISPLAY 0.872340 (4475 50);
PAINT GREEN (4475 50);
FORCEPROP 2 LAST CDS_LIB logical_power
J 0
(4450 125);
DISPLAY INVISIBLE (4450 125);
FORCEPROP 1 LAST PATH I34
J 0
(4525 125);
DISPLAY 0.872340 (4525 125);
PAINT AQUA (4525 125);
DISPLAY INVISIBLE (4525 125);
FORCEADD UNIVERSAL_GND..1
(200 925);
FORCEPROP 3 LASTPIN (200 975) SIG_NAME DELTA_L_GND_1\g
J 0
(210 985);
DISPLAY 0.659574 (210 985);
PAINT MONO (210 985);
DISPLAY INVISIBLE (210 985);
FORCEPROP 1 LAST HDL_POWER DELTA_L_GND_1
J 1
(225 850);
DISPLAY 0.872340 (225 850);
PAINT GREEN (225 850);
FORCEPROP 2 LAST CDS_LIB logical_power
J 0
(200 925);
DISPLAY INVISIBLE (200 925);
FORCEPROP 1 LAST PATH I35
J 0
(275 925);
DISPLAY 0.872340 (275 925);
PAINT AQUA (275 925);
DISPLAY INVISIBLE (275 925);
FORCEADD UNIVERSAL_GND..1
(200 1500);
FORCEPROP 3 LASTPIN (200 1550) SIG_NAME DELTA_L_GND_1\g
J 0
(210 1560);
DISPLAY 0.659574 (210 1560);
PAINT MONO (210 1560);
DISPLAY INVISIBLE (210 1560);
FORCEPROP 1 LAST HDL_POWER DELTA_L_GND_1
J 1
(225 1425);
DISPLAY 0.872340 (225 1425);
PAINT GREEN (225 1425);
FORCEPROP 2 LAST CDS_LIB logical_power
J 0
(200 1500);
DISPLAY INVISIBLE (200 1500);
FORCEPROP 1 LAST PATH I36
J 0
(275 1500);
DISPLAY 0.872340 (275 1500);
PAINT AQUA (275 1500);
DISPLAY INVISIBLE (275 1500);
FORCEADD UNIVERSAL_GND..1
(200 2350);
FORCEPROP 3 LASTPIN (200 2400) SIG_NAME DELTA_L_GND_1\g
J 0
(210 2410);
DISPLAY 0.659574 (210 2410);
PAINT MONO (210 2410);
DISPLAY INVISIBLE (210 2410);
FORCEPROP 1 LAST HDL_POWER DELTA_L_GND_1
J 1
(225 2275);
DISPLAY 0.872340 (225 2275);
PAINT GREEN (225 2275);
FORCEPROP 2 LAST CDS_LIB logical_power
J 0
(200 2350);
DISPLAY INVISIBLE (200 2350);
FORCEPROP 1 LAST PATH I37
J 0
(275 2350);
DISPLAY 0.872340 (275 2350);
PAINT AQUA (275 2350);
DISPLAY INVISIBLE (275 2350);
FORCEADD UNIVERSAL_GND..1
(1225 875);
FORCEPROP 3 LASTPIN (1225 925) SIG_NAME DELTA_L_GND_1\g
J 0
(1235 935);
DISPLAY 0.659574 (1235 935);
PAINT MONO (1235 935);
DISPLAY INVISIBLE (1235 935);
FORCEPROP 1 LAST HDL_POWER DELTA_L_GND_1
J 1
(1250 800);
DISPLAY 0.872340 (1250 800);
PAINT GREEN (1250 800);
FORCEPROP 2 LAST CDS_LIB logical_power
J 0
(1225 875);
DISPLAY INVISIBLE (1225 875);
FORCEPROP 1 LAST PATH I38
J 0
(1300 875);
DISPLAY 0.872340 (1300 875);
PAINT AQUA (1300 875);
DISPLAY INVISIBLE (1300 875);
FORCEADD PICOPROBE_BXA..1
(1775 1050);
FORCEPROP 1 LAST PART_NUMBER TP33
J 0
(1625 1203);
DISPLAY 0.723404 (1625 1203);
PAINT GREEN (1625 1203);
DISPLAY INVISIBLE (1625 1203);
FORCEPROP 1 LAST MATERIAL EMPTY
J 0
(1621 1155);
DISPLAY 0.723404 (1621 1155);
PAINT GREEN (1621 1155);
FORCEPROP 2 LAST VALUE DELTA-L 4.0
J 0
(1629 1296);
DISPLAY 1.021277 (1629 1296);
FORCEPROP 2 LAST PART_TYPE SMLF
J 0
(1629 1346);
DISPLAY 1.021277 (1629 1346);
FORCEPROP 1 LAST LOCATION J80
J 0
(1625 1250);
DISPLAY 0.723404 (1625 1250);
PAINT GREEN (1625 1250);
FORCEPROP 0 LASTPIN (2075 1050) $PN 1
J 0
(2085 1060);
DISPLAY 0.680851 (2085 1060);
PAINT MONO (2085 1060);
FORCEPROP 0 LASTPIN (2075 1100) $PN 2
J 0
(2085 1110);
DISPLAY 0.680851 (2085 1110);
PAINT MONO (2085 1110);
FORCEPROP 0 LASTPIN (1475 1100) $PN 3
J 2
(1465 1110);
DISPLAY 0.680851 (1465 1110);
PAINT MONO (1465 1110);
FORCEPROP 1 LAST NEEDS_NO_SIZE TRUE
J 0
(1775 1050);
DISPLAY 0.723404 (1775 1050);
PAINT GREEN (1775 1050);
DISPLAY INVISIBLE (1775 1050);
FORCEPROP 1 LAST CDS_LMAN_SYM_OUTLINE -150,100,150,-100
J 0
(1775 1050);
DISPLAY 0.468085 (1775 1050);
PAINT GREEN (1775 1050);
DISPLAY INVISIBLE (1775 1050);
FORCEPROP 2 LAST CDS_LIB pure_quanta
J 0
(1775 1050);
DISPLAY INVISIBLE (1775 1050);
FORCEPROP 1 LAST PATH I39
J 0
(1775 1050);
DISPLAY 0.723404 (1775 1050);
PAINT GREEN (1775 1050);
DISPLAY INVISIBLE (1775 1050);
FORCEPROP 0 LAST $SEC 1
J 0
(1650 1400);
DISPLAY 0.680851 (1650 1400);
PAINT MONO (1650 1400);
DISPLAY INVISIBLE (1650 1400);
FORCEPROP 0 LAST CDS_SEC 1
J 0
(1650 1400);
DISPLAY 1.021277 (1650 1400);
DISPLAY INVISIBLE (1650 1400);
FORCEADD PICOPROBE_BXA..1
(-2350 225);
FORCEPROP 1 LAST PART_NUMBER TP33
J 0
(-2500 378);
DISPLAY 0.723404 (-2500 378);
PAINT GREEN (-2500 378);
DISPLAY INVISIBLE (-2500 378);
FORCEPROP 2 LAST PART_TYPE SMLF
J 0
(-2496 521);
DISPLAY 1.021277 (-2496 521);
FORCEPROP 1 LAST MATERIAL EMPTY
J 0
(-2504 330);
DISPLAY 0.723404 (-2504 330);
PAINT GREEN (-2504 330);
FORCEPROP 2 LAST VALUE DELTA-L 4.0
J 0
(-2496 471);
DISPLAY 1.021277 (-2496 471);
FORCEPROP 1 LAST LOCATION J114
J 0
(-2500 425);
DISPLAY 0.723404 (-2500 425);
PAINT GREEN (-2500 425);
FORCEPROP 0 LASTPIN (-2050 225) $PN 1
J 0
(-2040 235);
DISPLAY 0.680851 (-2040 235);
PAINT MONO (-2040 235);
FORCEPROP 0 LASTPIN (-2050 275) $PN 2
J 0
(-2040 285);
DISPLAY 0.680851 (-2040 285);
PAINT MONO (-2040 285);
FORCEPROP 0 LASTPIN (-2650 275) $PN 3
J 2
(-2660 285);
DISPLAY 0.680851 (-2660 285);
PAINT MONO (-2660 285);
FORCEPROP 1 LAST NEEDS_NO_SIZE TRUE
J 0
(-2350 225);
DISPLAY 0.723404 (-2350 225);
PAINT GREEN (-2350 225);
DISPLAY INVISIBLE (-2350 225);
FORCEPROP 1 LAST CDS_LMAN_SYM_OUTLINE -150,100,150,-100
J 0
(-2350 225);
DISPLAY 0.468085 (-2350 225);
PAINT GREEN (-2350 225);
DISPLAY INVISIBLE (-2350 225);
FORCEPROP 2 LAST CDS_LIB pure_quanta
J 0
(-2350 225);
DISPLAY INVISIBLE (-2350 225);
FORCEPROP 1 LAST PATH I4
J 0
(-2350 225);
DISPLAY 0.723404 (-2350 225);
PAINT GREEN (-2350 225);
DISPLAY INVISIBLE (-2350 225);
FORCEPROP 0 LAST $SEC 1
J 0
(-2475 575);
DISPLAY 0.680851 (-2475 575);
PAINT MONO (-2475 575);
DISPLAY INVISIBLE (-2475 575);
FORCEPROP 0 LAST CDS_SEC 1
J 0
(-2475 575);
DISPLAY 1.021277 (-2475 575);
DISPLAY INVISIBLE (-2475 575);
FORCEADD UNIVERSAL_GND..1
(1225 1450);
FORCEPROP 3 LASTPIN (1225 1500) SIG_NAME DELTA_L_GND_1\g
J 0
(1235 1510);
DISPLAY 0.659574 (1235 1510);
PAINT MONO (1235 1510);
DISPLAY INVISIBLE (1235 1510);
FORCEPROP 1 LAST HDL_POWER DELTA_L_GND_1
J 1
(1250 1375);
DISPLAY 0.872340 (1250 1375);
PAINT GREEN (1250 1375);
FORCEPROP 2 LAST CDS_LIB logical_power
J 0
(1225 1450);
DISPLAY INVISIBLE (1225 1450);
FORCEPROP 1 LAST PATH I40
J 0
(1300 1450);
DISPLAY 0.872340 (1300 1450);
PAINT AQUA (1300 1450);
DISPLAY INVISIBLE (1300 1450);
FORCEADD UNIVERSAL_GND..1
(1225 2300);
FORCEPROP 3 LASTPIN (1225 2350) SIG_NAME DELTA_L_GND_1\g
J 0
(1235 2360);
DISPLAY 0.659574 (1235 2360);
PAINT MONO (1235 2360);
DISPLAY INVISIBLE (1235 2360);
FORCEPROP 1 LAST HDL_POWER DELTA_L_GND_1
J 1
(1250 2225);
DISPLAY 0.872340 (1250 2225);
PAINT GREEN (1250 2225);
FORCEPROP 2 LAST CDS_LIB logical_power
J 0
(1225 2300);
DISPLAY INVISIBLE (1225 2300);
FORCEPROP 1 LAST PATH I41
J 0
(1300 2300);
DISPLAY 0.872340 (1300 2300);
PAINT AQUA (1300 2300);
DISPLAY INVISIBLE (1300 2300);
FORCEADD PICOPROBE_BXA..1
(1775 1625);
FORCEPROP 1 LAST PART_NUMBER TP33
J 0
(1625 1778);
DISPLAY 0.723404 (1625 1778);
PAINT GREEN (1625 1778);
DISPLAY INVISIBLE (1625 1778);
FORCEPROP 1 LAST MATERIAL EMPTY
J 0
(1621 1730);
DISPLAY 0.723404 (1621 1730);
PAINT GREEN (1621 1730);
FORCEPROP 2 LAST VALUE DELTA-L 4.0
J 0
(1629 1871);
DISPLAY 1.021277 (1629 1871);
FORCEPROP 2 LAST PART_TYPE SMLF
J 0
(1629 1921);
DISPLAY 1.021277 (1629 1921);
FORCEPROP 1 LAST LOCATION J79
J 0
(1625 1825);
DISPLAY 0.723404 (1625 1825);
PAINT GREEN (1625 1825);
FORCEPROP 0 LASTPIN (2075 1625) $PN 1
J 0
(2085 1635);
DISPLAY 0.680851 (2085 1635);
PAINT MONO (2085 1635);
FORCEPROP 0 LASTPIN (2075 1675) $PN 2
J 0
(2085 1685);
DISPLAY 0.680851 (2085 1685);
PAINT MONO (2085 1685);
FORCEPROP 0 LASTPIN (1475 1675) $PN 3
J 2
(1465 1685);
DISPLAY 0.680851 (1465 1685);
PAINT MONO (1465 1685);
FORCEPROP 1 LAST NEEDS_NO_SIZE TRUE
J 0
(1775 1625);
DISPLAY 0.723404 (1775 1625);
PAINT GREEN (1775 1625);
DISPLAY INVISIBLE (1775 1625);
FORCEPROP 1 LAST CDS_LMAN_SYM_OUTLINE -150,100,150,-100
J 0
(1775 1625);
DISPLAY 0.468085 (1775 1625);
PAINT GREEN (1775 1625);
DISPLAY INVISIBLE (1775 1625);
FORCEPROP 2 LAST CDS_LIB pure_quanta
J 0
(1775 1625);
DISPLAY INVISIBLE (1775 1625);
FORCEPROP 1 LAST PATH I42
J 0
(1775 1625);
DISPLAY 0.723404 (1775 1625);
PAINT GREEN (1775 1625);
DISPLAY INVISIBLE (1775 1625);
FORCEPROP 0 LAST $SEC 1
J 0
(1650 1975);
DISPLAY 0.680851 (1650 1975);
PAINT MONO (1650 1975);
DISPLAY INVISIBLE (1650 1975);
FORCEPROP 0 LAST CDS_SEC 1
J 0
(1650 1975);
DISPLAY 1.021277 (1650 1975);
DISPLAY INVISIBLE (1650 1975);
FORCEADD PICOPROBE_BXA..1
(1775 2475);
FORCEPROP 1 LAST PART_NUMBER TP33
J 0
(1625 2628);
DISPLAY 0.723404 (1625 2628);
PAINT GREEN (1625 2628);
DISPLAY INVISIBLE (1625 2628);
FORCEPROP 1 LAST MATERIAL EMPTY
J 0
(1621 2580);
DISPLAY 0.723404 (1621 2580);
PAINT GREEN (1621 2580);
FORCEPROP 2 LAST PART_TYPE SMLF
J 0
(1629 2771);
DISPLAY 1.021277 (1629 2771);
FORCEPROP 2 LAST VALUE DELTA-L 4.0
J 0
(1629 2721);
DISPLAY 1.021277 (1629 2721);
FORCEPROP 1 LAST LOCATION J78
J 0
(1625 2675);
DISPLAY 0.723404 (1625 2675);
PAINT GREEN (1625 2675);
FORCEPROP 0 LASTPIN (2075 2475) $PN 1
J 0
(2085 2485);
DISPLAY 0.680851 (2085 2485);
PAINT MONO (2085 2485);
FORCEPROP 0 LASTPIN (2075 2525) $PN 2
J 0
(2085 2535);
DISPLAY 0.680851 (2085 2535);
PAINT MONO (2085 2535);
FORCEPROP 0 LASTPIN (1475 2525) $PN 3
J 2
(1465 2535);
DISPLAY 0.680851 (1465 2535);
PAINT MONO (1465 2535);
FORCEPROP 1 LAST NEEDS_NO_SIZE TRUE
J 0
(1775 2475);
DISPLAY 0.723404 (1775 2475);
PAINT GREEN (1775 2475);
DISPLAY INVISIBLE (1775 2475);
FORCEPROP 1 LAST CDS_LMAN_SYM_OUTLINE -150,100,150,-100
J 0
(1775 2475);
DISPLAY 0.468085 (1775 2475);
PAINT GREEN (1775 2475);
DISPLAY INVISIBLE (1775 2475);
FORCEPROP 2 LAST CDS_LIB pure_quanta
J 0
(1775 2475);
DISPLAY INVISIBLE (1775 2475);
FORCEPROP 1 LAST PATH I43
J 0
(1775 2475);
DISPLAY 0.723404 (1775 2475);
PAINT GREEN (1775 2475);
DISPLAY INVISIBLE (1775 2475);
FORCEPROP 0 LAST $SEC 1
J 0
(1650 2825);
DISPLAY 0.680851 (1650 2825);
PAINT MONO (1650 2825);
DISPLAY INVISIBLE (1650 2825);
FORCEPROP 0 LAST CDS_SEC 1
J 0
(1650 2825);
DISPLAY 1.021277 (1650 2825);
DISPLAY INVISIBLE (1650 2825);
FORCEADD UNIVERSAL_GND..1
(200 2925);
FORCEPROP 3 LASTPIN (200 2975) SIG_NAME DELTA_L_GND_1\g
J 0
(210 2985);
DISPLAY 0.659574 (210 2985);
PAINT MONO (210 2985);
DISPLAY INVISIBLE (210 2985);
FORCEPROP 1 LAST HDL_POWER DELTA_L_GND_1
J 1
(225 2850);
DISPLAY 0.872340 (225 2850);
PAINT GREEN (225 2850);
FORCEPROP 2 LAST CDS_LIB logical_power
J 0
(200 2925);
DISPLAY INVISIBLE (200 2925);
FORCEPROP 1 LAST PATH I44
J 0
(275 2925);
DISPLAY 0.872340 (275 2925);
PAINT AQUA (275 2925);
DISPLAY INVISIBLE (275 2925);
FORCEADD UNIVERSAL_GND..1
(200 3825);
FORCEPROP 3 LASTPIN (200 3875) SIG_NAME DELTA_L_GND_1\g
J 0
(210 3885);
DISPLAY 0.659574 (210 3885);
PAINT MONO (210 3885);
DISPLAY INVISIBLE (210 3885);
FORCEPROP 1 LAST HDL_POWER DELTA_L_GND_1
J 1
(225 3750);
DISPLAY 0.872340 (225 3750);
PAINT GREEN (225 3750);
FORCEPROP 2 LAST CDS_LIB logical_power
J 0
(200 3825);
DISPLAY INVISIBLE (200 3825);
FORCEPROP 1 LAST PATH I45
J 0
(275 3825);
DISPLAY 0.872340 (275 3825);
PAINT AQUA (275 3825);
DISPLAY INVISIBLE (275 3825);
FORCEADD UNIVERSAL_GND..1
(225 4400);
FORCEPROP 3 LASTPIN (225 4450) SIG_NAME DELTA_L_GND_1\g
J 0
(235 4460);
DISPLAY 0.659574 (235 4460);
PAINT MONO (235 4460);
DISPLAY INVISIBLE (235 4460);
FORCEPROP 1 LAST HDL_POWER DELTA_L_GND_1
J 1
(250 4325);
DISPLAY 0.872340 (250 4325);
PAINT GREEN (250 4325);
FORCEPROP 2 LAST CDS_LIB logical_power
J 0
(225 4400);
DISPLAY INVISIBLE (225 4400);
FORCEPROP 1 LAST PATH I46
J 0
(300 4400);
DISPLAY 0.872340 (300 4400);
PAINT AQUA (300 4400);
DISPLAY INVISIBLE (300 4400);
FORCEADD UNIVERSAL_GND..1
(1225 2875);
FORCEPROP 3 LASTPIN (1225 2925) SIG_NAME DELTA_L_GND_1\g
J 0
(1235 2935);
DISPLAY 0.659574 (1235 2935);
PAINT MONO (1235 2935);
DISPLAY INVISIBLE (1235 2935);
FORCEPROP 1 LAST HDL_POWER DELTA_L_GND_1
J 1
(1250 2800);
DISPLAY 0.872340 (1250 2800);
PAINT GREEN (1250 2800);
FORCEPROP 2 LAST CDS_LIB logical_power
J 0
(1225 2875);
DISPLAY INVISIBLE (1225 2875);
FORCEPROP 1 LAST PATH I47
J 0
(1300 2875);
DISPLAY 0.872340 (1300 2875);
PAINT AQUA (1300 2875);
DISPLAY INVISIBLE (1300 2875);
FORCEADD PICOPROBE_BXA..1
(1775 3050);
FORCEPROP 1 LAST PART_NUMBER TP33
J 0
(1625 3203);
DISPLAY 0.723404 (1625 3203);
PAINT GREEN (1625 3203);
DISPLAY INVISIBLE (1625 3203);
FORCEPROP 1 LAST MATERIAL EMPTY
J 0
(1621 3155);
DISPLAY 0.723404 (1621 3155);
PAINT GREEN (1621 3155);
FORCEPROP 2 LAST VALUE DELTA-L 4.0
J 0
(1629 3296);
DISPLAY 1.021277 (1629 3296);
FORCEPROP 2 LAST PART_TYPE SMLF
J 0
(1629 3346);
DISPLAY 1.021277 (1629 3346);
FORCEPROP 1 LAST LOCATION J77
J 0
(1625 3250);
DISPLAY 0.723404 (1625 3250);
PAINT GREEN (1625 3250);
FORCEPROP 0 LASTPIN (2075 3050) $PN 1
J 0
(2085 3060);
DISPLAY 0.680851 (2085 3060);
PAINT MONO (2085 3060);
FORCEPROP 0 LASTPIN (2075 3100) $PN 2
J 0
(2085 3110);
DISPLAY 0.680851 (2085 3110);
PAINT MONO (2085 3110);
FORCEPROP 0 LASTPIN (1475 3100) $PN 3
J 2
(1465 3110);
DISPLAY 0.680851 (1465 3110);
PAINT MONO (1465 3110);
FORCEPROP 2 LAST CDS_LIB pure_quanta
J 0
(1775 3050);
DISPLAY INVISIBLE (1775 3050);
FORCEPROP 1 LAST CDS_LMAN_SYM_OUTLINE -150,100,150,-100
J 0
(1775 3050);
DISPLAY 0.468085 (1775 3050);
PAINT GREEN (1775 3050);
DISPLAY INVISIBLE (1775 3050);
FORCEPROP 1 LAST NEEDS_NO_SIZE TRUE
J 0
(1775 3050);
DISPLAY 0.723404 (1775 3050);
PAINT GREEN (1775 3050);
DISPLAY INVISIBLE (1775 3050);
FORCEPROP 1 LAST PATH I48
J 0
(1775 3050);
DISPLAY 0.723404 (1775 3050);
PAINT GREEN (1775 3050);
DISPLAY INVISIBLE (1775 3050);
FORCEPROP 0 LAST $SEC 1
J 0
(1650 3400);
DISPLAY 0.680851 (1650 3400);
PAINT MONO (1650 3400);
DISPLAY INVISIBLE (1650 3400);
FORCEPROP 0 LAST CDS_SEC 1
J 0
(1650 3400);
DISPLAY 1.021277 (1650 3400);
DISPLAY INVISIBLE (1650 3400);
FORCEADD UNIVERSAL_GND..1
(1225 3775);
FORCEPROP 3 LASTPIN (1225 3825) SIG_NAME DELTA_L_GND_1\g
J 0
(1235 3835);
DISPLAY 0.659574 (1235 3835);
PAINT MONO (1235 3835);
DISPLAY INVISIBLE (1235 3835);
FORCEPROP 1 LAST HDL_POWER DELTA_L_GND_1
J 1
(1250 3700);
DISPLAY 0.872340 (1250 3700);
PAINT GREEN (1250 3700);
FORCEPROP 2 LAST CDS_LIB logical_power
J 0
(1225 3775);
DISPLAY INVISIBLE (1225 3775);
FORCEPROP 1 LAST PATH I49
J 0
(1300 3775);
DISPLAY 0.872340 (1300 3775);
PAINT AQUA (1300 3775);
DISPLAY INVISIBLE (1300 3775);
FORCEADD PICOPROBE_BXA..1
R 4
(-300 -300);
FORCEPROP 1 LAST PART_NUMBER TP33
R 2
J 0
(-146 -457);
DISPLAY 0.723404 (-146 -457);
PAINT GREEN (-146 -457);
DISPLAY INVISIBLE (-146 -457);
FORCEPROP 2 LAST VALUE DELTA-L 4.0
R 2
J 0
(-150 -500);
DISPLAY 1.021277 (-150 -500);
FORCEPROP 2 LAST PART_TYPE SMLF
R 2
J 0
(-150 -550);
DISPLAY 1.021277 (-150 -550);
FORCEPROP 1 LAST MATERIAL EMPTY
R 2
J 0
(-146 -405);
DISPLAY 0.723404 (-146 -405);
PAINT GREEN (-146 -405);
FORCEPROP 1 LAST LOCATION J117
R 2
J 0
(-146 -679);
DISPLAY 0.723404 (-146 -679);
PAINT GREEN (-146 -679);
FORCEPROP 0 LASTPIN (-600 -300) $PN 1
J 2
(-610 -310);
DISPLAY 0.680851 (-610 -310);
PAINT MONO (-610 -310);
FORCEPROP 0 LASTPIN (-600 -350) $PN 2
J 2
(-610 -360);
DISPLAY 0.680851 (-610 -360);
PAINT MONO (-610 -360);
FORCEPROP 0 LASTPIN (0 -350) $PN 3
J 0
(10 -360);
DISPLAY 0.680851 (10 -360);
PAINT MONO (10 -360);
FORCEPROP 2 LAST CDS_LIB pure_quanta
R 2
J 2
(-300 -300);
DISPLAY INVISIBLE (-300 -300);
FORCEPROP 1 LAST CDS_LMAN_SYM_OUTLINE -150,100,150,-100
R 2
J 0
(-300 -300);
DISPLAY 0.468085 (-300 -300);
PAINT GREEN (-300 -300);
DISPLAY INVISIBLE (-300 -300);
FORCEPROP 1 LAST NEEDS_NO_SIZE TRUE
R 2
J 0
(-300 -300);
DISPLAY 0.723404 (-300 -300);
PAINT GREEN (-300 -300);
DISPLAY INVISIBLE (-300 -300);
FORCEPROP 1 LAST PATH I5
R 2
J 0
(-300 -300);
DISPLAY 0.723404 (-300 -300);
PAINT GREEN (-300 -300);
DISPLAY INVISIBLE (-300 -300);
FORCEPROP 0 LAST $SEC 1
R 2
J 2
(-125 -725);
DISPLAY 0.680851 (-125 -725);
PAINT MONO (-125 -725);
DISPLAY INVISIBLE (-125 -725);
FORCEPROP 0 LAST CDS_SEC 1
R 2
J 2
(-125 -725);
DISPLAY 1.021277 (-125 -725);
DISPLAY INVISIBLE (-125 -725);
FORCEADD UNIVERSAL_GND..1
(1225 4350);
FORCEPROP 3 LASTPIN (1225 4400) SIG_NAME DELTA_L_GND_1\g
J 0
(1235 4410);
DISPLAY 0.659574 (1235 4410);
PAINT MONO (1235 4410);
DISPLAY INVISIBLE (1235 4410);
FORCEPROP 1 LAST HDL_POWER DELTA_L_GND_1
J 1
(1250 4275);
DISPLAY 0.872340 (1250 4275);
PAINT GREEN (1250 4275);
FORCEPROP 2 LAST CDS_LIB logical_power
J 0
(1225 4350);
DISPLAY INVISIBLE (1225 4350);
FORCEPROP 1 LAST PATH I50
J 0
(1300 4350);
DISPLAY 0.872340 (1300 4350);
PAINT AQUA (1300 4350);
DISPLAY INVISIBLE (1300 4350);
FORCEADD PICOPROBE_BXA..1
(1775 3950);
FORCEPROP 1 LAST PART_NUMBER TP33
J 0
(1625 4103);
DISPLAY 0.723404 (1625 4103);
PAINT GREEN (1625 4103);
DISPLAY INVISIBLE (1625 4103);
FORCEPROP 1 LAST MATERIAL EMPTY
J 0
(1621 4055);
DISPLAY 0.723404 (1621 4055);
PAINT GREEN (1621 4055);
FORCEPROP 2 LAST PART_TYPE SMLF
J 0
(1629 4246);
DISPLAY 1.021277 (1629 4246);
FORCEPROP 2 LAST VALUE DELTA-L 4.0
J 0
(1629 4196);
DISPLAY 1.021277 (1629 4196);
FORCEPROP 1 LAST LOCATION J76
J 0
(1625 4150);
DISPLAY 0.723404 (1625 4150);
PAINT GREEN (1625 4150);
FORCEPROP 0 LASTPIN (2075 3950) $PN 1
J 0
(2085 3960);
DISPLAY 0.680851 (2085 3960);
PAINT MONO (2085 3960);
FORCEPROP 0 LASTPIN (2075 4000) $PN 2
J 0
(2085 4010);
DISPLAY 0.680851 (2085 4010);
PAINT MONO (2085 4010);
FORCEPROP 0 LASTPIN (1475 4000) $PN 3
J 2
(1465 4010);
DISPLAY 0.680851 (1465 4010);
PAINT MONO (1465 4010);
FORCEPROP 2 LAST CDS_LIB pure_quanta
J 0
(1775 3950);
DISPLAY INVISIBLE (1775 3950);
FORCEPROP 1 LAST CDS_LMAN_SYM_OUTLINE -150,100,150,-100
J 0
(1775 3950);
DISPLAY 0.468085 (1775 3950);
PAINT GREEN (1775 3950);
DISPLAY INVISIBLE (1775 3950);
FORCEPROP 1 LAST NEEDS_NO_SIZE TRUE
J 0
(1775 3950);
DISPLAY 0.723404 (1775 3950);
PAINT GREEN (1775 3950);
DISPLAY INVISIBLE (1775 3950);
FORCEPROP 1 LAST PATH I51
J 0
(1775 3950);
DISPLAY 0.723404 (1775 3950);
PAINT GREEN (1775 3950);
DISPLAY INVISIBLE (1775 3950);
FORCEPROP 0 LAST $SEC 1
J 0
(1650 4300);
DISPLAY 0.680851 (1650 4300);
PAINT MONO (1650 4300);
DISPLAY INVISIBLE (1650 4300);
FORCEPROP 0 LAST CDS_SEC 1
J 0
(1650 4300);
DISPLAY 1.021277 (1650 4300);
DISPLAY INVISIBLE (1650 4300);
FORCEADD PICOPROBE_BXA..1
(1775 4525);
FORCEPROP 1 LAST PART_NUMBER TP33
J 0
(1621 4682);
DISPLAY 0.723404 (1621 4682);
PAINT GREEN (1621 4682);
DISPLAY INVISIBLE (1621 4682);
FORCEPROP 1 LAST MATERIAL EMPTY
J 0
(1621 4630);
DISPLAY 0.723404 (1621 4630);
PAINT GREEN (1621 4630);
FORCEPROP 2 LAST VALUE DELTA-L 4.0
J 0
(1629 4771);
DISPLAY 1.021277 (1629 4771);
FORCEPROP 2 LAST PART_TYPE SMLF
J 0
(1629 4821);
DISPLAY 1.021277 (1629 4821);
FORCEPROP 1 LAST LOCATION J75
J 0
(1625 4725);
DISPLAY 0.723404 (1625 4725);
PAINT GREEN (1625 4725);
FORCEPROP 0 LASTPIN (2075 4525) $PN 1
J 0
(2085 4535);
DISPLAY 0.680851 (2085 4535);
PAINT MONO (2085 4535);
FORCEPROP 0 LASTPIN (2075 4575) $PN 2
J 0
(2085 4585);
DISPLAY 0.680851 (2085 4585);
PAINT MONO (2085 4585);
FORCEPROP 0 LASTPIN (1475 4575) $PN 3
J 2
(1465 4585);
DISPLAY 0.680851 (1465 4585);
PAINT MONO (1465 4585);
FORCEPROP 1 LAST CDS_LMAN_SYM_OUTLINE -150,100,150,-100
J 0
(1775 4525);
DISPLAY 0.468085 (1775 4525);
PAINT GREEN (1775 4525);
DISPLAY INVISIBLE (1775 4525);
FORCEPROP 1 LAST NEEDS_NO_SIZE TRUE
J 0
(1775 4525);
DISPLAY 0.723404 (1775 4525);
PAINT GREEN (1775 4525);
DISPLAY INVISIBLE (1775 4525);
FORCEPROP 2 LAST CDS_LIB pure_quanta
J 0
(1775 4525);
DISPLAY INVISIBLE (1775 4525);
FORCEPROP 1 LAST PATH I52
J 0
(1775 4525);
DISPLAY 0.723404 (1775 4525);
PAINT GREEN (1775 4525);
DISPLAY INVISIBLE (1775 4525);
FORCEPROP 0 LAST $SEC 1
J 0
(1650 4875);
DISPLAY 0.680851 (1650 4875);
PAINT MONO (1650 4875);
DISPLAY INVISIBLE (1650 4875);
FORCEPROP 0 LAST CDS_SEC 1
J 0
(1650 4875);
DISPLAY 1.021277 (1650 4875);
DISPLAY INVISIBLE (1650 4875);
FORCEADD PICOPROBE_BXA..1
R 4
(3825 1100);
FORCEPROP 1 LAST PART_NUMBER TP33
R 2
J 0
(3979 943);
DISPLAY 0.723404 (3979 943);
PAINT GREEN (3979 943);
DISPLAY INVISIBLE (3979 943);
FORCEPROP 1 LAST MATERIAL EMPTY
R 2
J 0
(3979 995);
DISPLAY 0.723404 (3979 995);
PAINT GREEN (3979 995);
FORCEPROP 2 LAST PART_TYPE SMLF
R 2
J 0
(3975 850);
DISPLAY 1.021277 (3975 850);
FORCEPROP 2 LAST VALUE DELTA-L 4.0
R 2
J 0
(3975 900);
DISPLAY 1.021277 (3975 900);
FORCEPROP 1 LAST LOCATION J86
R 2
J 0
(3979 721);
DISPLAY 0.723404 (3979 721);
PAINT GREEN (3979 721);
FORCEPROP 0 LASTPIN (3525 1100) $PN 1
J 2
(3515 1090);
DISPLAY 0.680851 (3515 1090);
PAINT MONO (3515 1090);
FORCEPROP 0 LASTPIN (3525 1050) $PN 2
J 2
(3515 1040);
DISPLAY 0.680851 (3515 1040);
PAINT MONO (3515 1040);
FORCEPROP 0 LASTPIN (4125 1050) $PN 3
J 0
(4135 1040);
DISPLAY 0.680851 (4135 1040);
PAINT MONO (4135 1040);
FORCEPROP 1 LAST NEEDS_NO_SIZE TRUE
R 2
J 0
(3825 1100);
DISPLAY 0.723404 (3825 1100);
PAINT GREEN (3825 1100);
DISPLAY INVISIBLE (3825 1100);
FORCEPROP 1 LAST CDS_LMAN_SYM_OUTLINE -150,100,150,-100
R 2
J 0
(3825 1100);
DISPLAY 0.468085 (3825 1100);
PAINT GREEN (3825 1100);
DISPLAY INVISIBLE (3825 1100);
FORCEPROP 2 LAST CDS_LIB pure_quanta
R 2
J 2
(3825 1100);
DISPLAY INVISIBLE (3825 1100);
FORCEPROP 1 LAST PATH I53
R 2
J 0
(3825 1100);
DISPLAY 0.723404 (3825 1100);
PAINT GREEN (3825 1100);
DISPLAY INVISIBLE (3825 1100);
FORCEPROP 0 LAST $SEC 1
R 2
J 2
(4000 675);
DISPLAY 0.680851 (4000 675);
PAINT MONO (4000 675);
DISPLAY INVISIBLE (4000 675);
FORCEPROP 0 LAST CDS_SEC 1
R 2
J 2
(4000 675);
DISPLAY 1.021277 (4000 675);
DISPLAY INVISIBLE (4000 675);
FORCEADD PICOPROBE_BXA..1
R 4
(3825 1675);
FORCEPROP 1 LAST PART_NUMBER TP33
R 2
J 0
(3979 1518);
DISPLAY 0.723404 (3979 1518);
PAINT GREEN (3979 1518);
DISPLAY INVISIBLE (3979 1518);
FORCEPROP 2 LAST VALUE DELTA-L 4.0
R 2
J 0
(3975 1475);
DISPLAY 1.021277 (3975 1475);
FORCEPROP 2 LAST PART_TYPE SMLF
R 2
J 0
(3975 1425);
DISPLAY 1.021277 (3975 1425);
FORCEPROP 1 LAST MATERIAL EMPTY
R 2
J 0
(3979 1570);
DISPLAY 0.723404 (3979 1570);
PAINT GREEN (3979 1570);
FORCEPROP 1 LAST LOCATION J85
R 2
J 0
(3979 1296);
DISPLAY 0.723404 (3979 1296);
PAINT GREEN (3979 1296);
FORCEPROP 0 LASTPIN (3525 1675) $PN 1
J 2
(3515 1665);
DISPLAY 0.680851 (3515 1665);
PAINT MONO (3515 1665);
FORCEPROP 0 LASTPIN (3525 1625) $PN 2
J 2
(3515 1615);
DISPLAY 0.680851 (3515 1615);
PAINT MONO (3515 1615);
FORCEPROP 0 LASTPIN (4125 1625) $PN 3
J 0
(4135 1615);
DISPLAY 0.680851 (4135 1615);
PAINT MONO (4135 1615);
FORCEPROP 1 LAST NEEDS_NO_SIZE TRUE
R 2
J 0
(3825 1675);
DISPLAY 0.723404 (3825 1675);
PAINT GREEN (3825 1675);
DISPLAY INVISIBLE (3825 1675);
FORCEPROP 1 LAST CDS_LMAN_SYM_OUTLINE -150,100,150,-100
R 2
J 0
(3825 1675);
DISPLAY 0.468085 (3825 1675);
PAINT GREEN (3825 1675);
DISPLAY INVISIBLE (3825 1675);
FORCEPROP 2 LAST CDS_LIB pure_quanta
R 2
J 2
(3825 1675);
DISPLAY INVISIBLE (3825 1675);
FORCEPROP 1 LAST PATH I54
R 2
J 0
(3825 1675);
DISPLAY 0.723404 (3825 1675);
PAINT GREEN (3825 1675);
DISPLAY INVISIBLE (3825 1675);
FORCEPROP 0 LAST $SEC 1
R 2
J 2
(4000 1250);
DISPLAY 0.680851 (4000 1250);
PAINT MONO (4000 1250);
DISPLAY INVISIBLE (4000 1250);
FORCEPROP 0 LAST CDS_SEC 1
R 2
J 2
(4000 1250);
DISPLAY 1.021277 (4000 1250);
DISPLAY INVISIBLE (4000 1250);
FORCEADD PICOPROBE_BXA..1
R 4
(3825 2525);
FORCEPROP 1 LAST PART_NUMBER TP33
R 2
J 0
(3979 2368);
DISPLAY 0.723404 (3979 2368);
PAINT GREEN (3979 2368);
DISPLAY INVISIBLE (3979 2368);
FORCEPROP 2 LAST VALUE DELTA-L 4.0
R 2
J 0
(3975 2325);
DISPLAY 1.021277 (3975 2325);
FORCEPROP 2 LAST PART_TYPE SMLF
R 2
J 0
(3975 2275);
DISPLAY 1.021277 (3975 2275);
FORCEPROP 1 LAST MATERIAL EMPTY
R 2
J 0
(3979 2420);
DISPLAY 0.723404 (3979 2420);
PAINT GREEN (3979 2420);
FORCEPROP 1 LAST LOCATION J84
R 2
J 0
(3979 2146);
DISPLAY 0.723404 (3979 2146);
PAINT GREEN (3979 2146);
FORCEPROP 0 LASTPIN (3525 2525) $PN 1
J 2
(3515 2515);
DISPLAY 0.680851 (3515 2515);
PAINT MONO (3515 2515);
FORCEPROP 0 LASTPIN (3525 2475) $PN 2
J 2
(3515 2465);
DISPLAY 0.680851 (3515 2465);
PAINT MONO (3515 2465);
FORCEPROP 0 LASTPIN (4125 2475) $PN 3
J 0
(4135 2465);
DISPLAY 0.680851 (4135 2465);
PAINT MONO (4135 2465);
FORCEPROP 1 LAST NEEDS_NO_SIZE TRUE
R 2
J 0
(3825 2525);
DISPLAY 0.723404 (3825 2525);
PAINT GREEN (3825 2525);
DISPLAY INVISIBLE (3825 2525);
FORCEPROP 1 LAST CDS_LMAN_SYM_OUTLINE -150,100,150,-100
R 2
J 0
(3825 2525);
DISPLAY 0.468085 (3825 2525);
PAINT GREEN (3825 2525);
DISPLAY INVISIBLE (3825 2525);
FORCEPROP 2 LAST CDS_LIB pure_quanta
R 2
J 2
(3825 2525);
DISPLAY INVISIBLE (3825 2525);
FORCEPROP 1 LAST PATH I55
R 2
J 0
(3825 2525);
DISPLAY 0.723404 (3825 2525);
PAINT GREEN (3825 2525);
DISPLAY INVISIBLE (3825 2525);
FORCEPROP 0 LAST $SEC 1
R 2
J 2
(4000 2100);
DISPLAY 0.680851 (4000 2100);
PAINT MONO (4000 2100);
DISPLAY INVISIBLE (4000 2100);
FORCEPROP 0 LAST CDS_SEC 1
R 2
J 2
(4000 2100);
DISPLAY 1.021277 (4000 2100);
DISPLAY INVISIBLE (4000 2100);
FORCEADD PICOPROBE_BXA..1
R 4
(3825 3100);
FORCEPROP 1 LAST PART_NUMBER TP33
R 2
J 0
(3979 2943);
DISPLAY 0.723404 (3979 2943);
PAINT GREEN (3979 2943);
DISPLAY INVISIBLE (3979 2943);
FORCEPROP 1 LAST MATERIAL EMPTY
R 2
J 0
(3979 2995);
DISPLAY 0.723404 (3979 2995);
PAINT GREEN (3979 2995);
FORCEPROP 2 LAST PART_TYPE SMLF
R 2
J 0
(3975 2850);
DISPLAY 1.021277 (3975 2850);
FORCEPROP 2 LAST VALUE DELTA-L 4.0
R 2
J 0
(3975 2900);
DISPLAY 1.021277 (3975 2900);
FORCEPROP 1 LAST LOCATION J83
R 2
J 0
(3979 2721);
DISPLAY 0.723404 (3979 2721);
PAINT GREEN (3979 2721);
FORCEPROP 0 LASTPIN (3525 3100) $PN 1
J 2
(3515 3090);
DISPLAY 0.680851 (3515 3090);
PAINT MONO (3515 3090);
FORCEPROP 0 LASTPIN (3525 3050) $PN 2
J 2
(3515 3040);
DISPLAY 0.680851 (3515 3040);
PAINT MONO (3515 3040);
FORCEPROP 0 LASTPIN (4125 3050) $PN 3
J 0
(4135 3040);
DISPLAY 0.680851 (4135 3040);
PAINT MONO (4135 3040);
FORCEPROP 1 LAST NEEDS_NO_SIZE TRUE
R 2
J 0
(3825 3100);
DISPLAY 0.723404 (3825 3100);
PAINT GREEN (3825 3100);
DISPLAY INVISIBLE (3825 3100);
FORCEPROP 1 LAST CDS_LMAN_SYM_OUTLINE -150,100,150,-100
R 2
J 0
(3825 3100);
DISPLAY 0.468085 (3825 3100);
PAINT GREEN (3825 3100);
DISPLAY INVISIBLE (3825 3100);
FORCEPROP 2 LAST CDS_LIB pure_quanta
R 2
J 2
(3825 3100);
DISPLAY INVISIBLE (3825 3100);
FORCEPROP 1 LAST PATH I56
R 2
J 0
(3825 3100);
DISPLAY 0.723404 (3825 3100);
PAINT GREEN (3825 3100);
DISPLAY INVISIBLE (3825 3100);
FORCEPROP 0 LAST $SEC 1
R 2
J 2
(4000 2675);
DISPLAY 0.680851 (4000 2675);
PAINT MONO (4000 2675);
DISPLAY INVISIBLE (4000 2675);
FORCEPROP 0 LAST CDS_SEC 1
R 2
J 2
(4000 2675);
DISPLAY 1.021277 (4000 2675);
DISPLAY INVISIBLE (4000 2675);
FORCEADD PICOPROBE_BXA..1
R 4
(3825 4000);
FORCEPROP 1 LAST PART_NUMBER TP33
R 2
J 0
(3979 3843);
DISPLAY 0.723404 (3979 3843);
PAINT GREEN (3979 3843);
DISPLAY INVISIBLE (3979 3843);
FORCEPROP 1 LAST MATERIAL EMPTY
R 2
J 0
(3979 3895);
DISPLAY 0.723404 (3979 3895);
PAINT GREEN (3979 3895);
FORCEPROP 2 LAST PART_TYPE SMLF
R 2
J 0
(3975 3750);
DISPLAY 1.021277 (3975 3750);
FORCEPROP 2 LAST VALUE DELTA-L 4.0
R 2
J 0
(3975 3800);
DISPLAY 1.021277 (3975 3800);
FORCEPROP 1 LAST LOCATION J82
R 2
J 0
(3983 3667);
DISPLAY 0.723404 (3983 3667);
PAINT GREEN (3983 3667);
FORCEPROP 0 LASTPIN (3525 4000) $PN 1
J 2
(3515 3990);
DISPLAY 0.680851 (3515 3990);
PAINT MONO (3515 3990);
FORCEPROP 0 LASTPIN (3525 3950) $PN 2
J 2
(3515 3940);
DISPLAY 0.680851 (3515 3940);
PAINT MONO (3515 3940);
FORCEPROP 0 LASTPIN (4125 3950) $PN 3
J 0
(4135 3940);
DISPLAY 0.680851 (4135 3940);
PAINT MONO (4135 3940);
FORCEPROP 1 LAST NEEDS_NO_SIZE TRUE
R 2
J 0
(3825 4000);
DISPLAY 0.723404 (3825 4000);
PAINT GREEN (3825 4000);
DISPLAY INVISIBLE (3825 4000);
FORCEPROP 1 LAST CDS_LMAN_SYM_OUTLINE -150,100,150,-100
R 2
J 0
(3825 4000);
DISPLAY 0.468085 (3825 4000);
PAINT GREEN (3825 4000);
DISPLAY INVISIBLE (3825 4000);
FORCEPROP 2 LAST CDS_LIB pure_quanta
R 2
J 0
(3825 4000);
DISPLAY INVISIBLE (3825 4000);
FORCEPROP 1 LAST PATH I57
R 2
J 0
(3825 4000);
DISPLAY 0.723404 (3825 4000);
PAINT GREEN (3825 4000);
DISPLAY INVISIBLE (3825 4000);
FORCEPROP 0 LAST $SEC 1
R 2
J 2
(4000 3625);
DISPLAY 0.680851 (4000 3625);
PAINT MONO (4000 3625);
DISPLAY INVISIBLE (4000 3625);
FORCEPROP 0 LAST CDS_SEC 1
R 2
J 2
(4000 3625);
DISPLAY 1.021277 (4000 3625);
DISPLAY INVISIBLE (4000 3625);
FORCEADD PICOPROBE_BXA..1
R 4
(3825 4575);
FORCEPROP 1 LAST PART_NUMBER TP33
R 2
J 0
(3979 4418);
DISPLAY 0.723404 (3979 4418);
PAINT GREEN (3979 4418);
DISPLAY INVISIBLE (3979 4418);
FORCEPROP 2 LAST PART_TYPE SMLF
R 2
J 0
(3975 4325);
DISPLAY 1.021277 (3975 4325);
FORCEPROP 1 LAST MATERIAL EMPTY
R 2
J 0
(3979 4470);
DISPLAY 0.723404 (3979 4470);
PAINT GREEN (3979 4470);
FORCEPROP 2 LAST VALUE DELTA-L 4.0
R 2
J 0
(3975 4375);
DISPLAY 1.021277 (3975 4375);
FORCEPROP 1 LAST LOCATION J81
R 2
J 0
(3983 4242);
DISPLAY 0.723404 (3983 4242);
PAINT GREEN (3983 4242);
FORCEPROP 0 LASTPIN (3525 4575) $PN 1
J 2
(3515 4565);
DISPLAY 0.680851 (3515 4565);
PAINT MONO (3515 4565);
FORCEPROP 0 LASTPIN (3525 4525) $PN 2
J 2
(3515 4515);
DISPLAY 0.680851 (3515 4515);
PAINT MONO (3515 4515);
FORCEPROP 0 LASTPIN (4125 4525) $PN 3
J 0
(4135 4515);
DISPLAY 0.680851 (4135 4515);
PAINT MONO (4135 4515);
FORCEPROP 2 LAST CDS_LIB pure_quanta
R 2
J 0
(3825 4575);
DISPLAY INVISIBLE (3825 4575);
FORCEPROP 1 LAST CDS_LMAN_SYM_OUTLINE -150,100,150,-100
R 2
J 0
(3825 4575);
DISPLAY 0.468085 (3825 4575);
PAINT GREEN (3825 4575);
DISPLAY INVISIBLE (3825 4575);
FORCEPROP 1 LAST NEEDS_NO_SIZE TRUE
R 2
J 0
(3825 4575);
DISPLAY 0.723404 (3825 4575);
PAINT GREEN (3825 4575);
DISPLAY INVISIBLE (3825 4575);
FORCEPROP 1 LAST PATH I58
R 2
J 0
(3825 4575);
DISPLAY 0.723404 (3825 4575);
PAINT GREEN (3825 4575);
DISPLAY INVISIBLE (3825 4575);
FORCEPROP 0 LAST $SEC 1
R 2
J 2
(4000 4200);
DISPLAY 0.680851 (4000 4200);
PAINT MONO (4000 4200);
DISPLAY INVISIBLE (4000 4200);
FORCEPROP 0 LAST CDS_SEC 1
R 2
J 2
(4000 4200);
DISPLAY 1.021277 (4000 4200);
DISPLAY INVISIBLE (4000 4200);
FORCEADD UNIVERSAL_GND..1
(4375 925);
FORCEPROP 3 LASTPIN (4375 975) SIG_NAME DELTA_L_GND_1\g
J 0
(4385 985);
DISPLAY 0.659574 (4385 985);
PAINT MONO (4385 985);
DISPLAY INVISIBLE (4385 985);
FORCEPROP 1 LAST HDL_POWER DELTA_L_GND_1
J 1
(4400 850);
DISPLAY 0.872340 (4400 850);
PAINT GREEN (4400 850);
FORCEPROP 2 LAST CDS_LIB logical_power
J 0
(4375 925);
DISPLAY INVISIBLE (4375 925);
FORCEPROP 1 LAST PATH I59
J 0
(4450 925);
DISPLAY 0.872340 (4450 925);
PAINT AQUA (4450 925);
DISPLAY INVISIBLE (4450 925);
FORCEADD PICOPROBE_BXA..1
R 4
(-300 275);
FORCEPROP 1 LAST PART_NUMBER TP33
R 2
J 0
(-146 118);
DISPLAY 0.723404 (-146 118);
PAINT GREEN (-146 118);
DISPLAY INVISIBLE (-146 118);
FORCEPROP 2 LAST VALUE DELTA-L 4.0
R 2
J 0
(-150 75);
DISPLAY 1.021277 (-150 75);
FORCEPROP 2 LAST PART_TYPE SMLF
R 2
J 0
(-150 25);
DISPLAY 1.021277 (-150 25);
FORCEPROP 1 LAST MATERIAL EMPTY
R 2
J 0
(-146 170);
DISPLAY 0.723404 (-146 170);
PAINT GREEN (-146 170);
FORCEPROP 1 LAST LOCATION J116
R 2
J 0
(-146 -104);
DISPLAY 0.723404 (-146 -104);
PAINT GREEN (-146 -104);
FORCEPROP 0 LASTPIN (-600 275) $PN 1
J 2
(-610 265);
DISPLAY 0.680851 (-610 265);
PAINT MONO (-610 265);
FORCEPROP 0 LASTPIN (-600 225) $PN 2
J 2
(-610 215);
DISPLAY 0.680851 (-610 215);
PAINT MONO (-610 215);
FORCEPROP 0 LASTPIN (0 225) $PN 3
J 0
(10 215);
DISPLAY 0.680851 (10 215);
PAINT MONO (10 215);
FORCEPROP 2 LAST CDS_LIB pure_quanta
R 2
J 2
(-300 275);
DISPLAY INVISIBLE (-300 275);
FORCEPROP 1 LAST CDS_LMAN_SYM_OUTLINE -150,100,150,-100
R 2
J 0
(-300 275);
DISPLAY 0.468085 (-300 275);
PAINT GREEN (-300 275);
DISPLAY INVISIBLE (-300 275);
FORCEPROP 1 LAST NEEDS_NO_SIZE TRUE
R 2
J 0
(-300 275);
DISPLAY 0.723404 (-300 275);
PAINT GREEN (-300 275);
DISPLAY INVISIBLE (-300 275);
FORCEPROP 1 LAST PATH I6
R 2
J 0
(-300 275);
DISPLAY 0.723404 (-300 275);
PAINT GREEN (-300 275);
DISPLAY INVISIBLE (-300 275);
FORCEPROP 0 LAST $SEC 1
R 2
J 2
(-125 -150);
DISPLAY 0.680851 (-125 -150);
PAINT MONO (-125 -150);
DISPLAY INVISIBLE (-125 -150);
FORCEPROP 0 LAST CDS_SEC 1
R 2
J 2
(-125 -150);
DISPLAY 1.021277 (-125 -150);
DISPLAY INVISIBLE (-125 -150);
FORCEADD UNIVERSAL_GND..1
(4375 1500);
FORCEPROP 3 LASTPIN (4375 1550) SIG_NAME DELTA_L_GND_1\g
J 0
(4385 1560);
DISPLAY 0.659574 (4385 1560);
PAINT MONO (4385 1560);
DISPLAY INVISIBLE (4385 1560);
FORCEPROP 1 LAST HDL_POWER DELTA_L_GND_1
J 1
(4400 1425);
DISPLAY 0.872340 (4400 1425);
PAINT GREEN (4400 1425);
FORCEPROP 2 LAST CDS_LIB logical_power
J 0
(4375 1500);
DISPLAY INVISIBLE (4375 1500);
FORCEPROP 1 LAST PATH I60
J 0
(4450 1500);
DISPLAY 0.872340 (4450 1500);
PAINT AQUA (4450 1500);
DISPLAY INVISIBLE (4450 1500);
FORCEADD UNIVERSAL_GND..1
(4375 2350);
FORCEPROP 3 LASTPIN (4375 2400) SIG_NAME DELTA_L_GND_1\g
J 0
(4385 2410);
DISPLAY 0.659574 (4385 2410);
PAINT MONO (4385 2410);
DISPLAY INVISIBLE (4385 2410);
FORCEPROP 1 LAST HDL_POWER DELTA_L_GND_1
J 1
(4400 2275);
DISPLAY 0.872340 (4400 2275);
PAINT GREEN (4400 2275);
FORCEPROP 2 LAST CDS_LIB logical_power
J 0
(4375 2350);
DISPLAY INVISIBLE (4375 2350);
FORCEPROP 1 LAST PATH I61
J 0
(4450 2350);
DISPLAY 0.872340 (4450 2350);
PAINT AQUA (4450 2350);
DISPLAY INVISIBLE (4450 2350);
FORCEADD UNIVERSAL_GND..1
(4375 2925);
FORCEPROP 3 LASTPIN (4375 2975) SIG_NAME DELTA_L_GND_1\g
J 0
(4385 2985);
DISPLAY 0.659574 (4385 2985);
PAINT MONO (4385 2985);
DISPLAY INVISIBLE (4385 2985);
FORCEPROP 1 LAST HDL_POWER DELTA_L_GND_1
J 1
(4400 2850);
DISPLAY 0.872340 (4400 2850);
PAINT GREEN (4400 2850);
FORCEPROP 2 LAST CDS_LIB logical_power
J 0
(4375 2925);
DISPLAY INVISIBLE (4375 2925);
FORCEPROP 1 LAST PATH I62
J 0
(4450 2925);
DISPLAY 0.872340 (4450 2925);
PAINT AQUA (4450 2925);
DISPLAY INVISIBLE (4450 2925);
FORCEADD UNIVERSAL_GND..1
(4375 3825);
FORCEPROP 3 LASTPIN (4375 3875) SIG_NAME DELTA_L_GND_1\g
J 0
(4385 3885);
DISPLAY 0.659574 (4385 3885);
PAINT MONO (4385 3885);
DISPLAY INVISIBLE (4385 3885);
FORCEPROP 1 LAST HDL_POWER DELTA_L_GND_1
J 1
(4400 3750);
DISPLAY 0.872340 (4400 3750);
PAINT GREEN (4400 3750);
FORCEPROP 2 LAST CDS_LIB logical_power
J 0
(4375 3825);
DISPLAY INVISIBLE (4375 3825);
FORCEPROP 1 LAST PATH I63
J 0
(4450 3825);
DISPLAY 0.872340 (4450 3825);
PAINT AQUA (4450 3825);
DISPLAY INVISIBLE (4450 3825);
FORCEADD UNIVERSAL_GND..1
(4375 4400);
FORCEPROP 3 LASTPIN (4375 4450) SIG_NAME DELTA_L_GND_1\g
J 0
(4385 4460);
DISPLAY 0.659574 (4385 4460);
PAINT MONO (4385 4460);
DISPLAY INVISIBLE (4385 4460);
FORCEPROP 1 LAST HDL_POWER DELTA_L_GND_1
J 1
(4400 4325);
DISPLAY 0.872340 (4400 4325);
PAINT GREEN (4400 4325);
FORCEPROP 2 LAST CDS_LIB logical_power
J 0
(4375 4400);
DISPLAY INVISIBLE (4375 4400);
FORCEPROP 1 LAST PATH I64
J 0
(4450 4400);
DISPLAY 0.872340 (4450 4400);
PAINT AQUA (4450 4400);
DISPLAY INVISIBLE (4450 4400);
FORCEADD UNIVERSAL_GND..1
(-2950 875);
FORCEPROP 3 LASTPIN (-2950 925) SIG_NAME DELTA_L_GND_1\g
J 0
(-2940 935);
DISPLAY 0.659574 (-2940 935);
PAINT MONO (-2940 935);
DISPLAY INVISIBLE (-2940 935);
FORCEPROP 1 LAST HDL_POWER DELTA_L_GND_1
J 1
(-2925 800);
DISPLAY 0.872340 (-2925 800);
PAINT GREEN (-2925 800);
FORCEPROP 2 LAST CDS_LIB logical_power
J 0
(-2950 875);
DISPLAY INVISIBLE (-2950 875);
FORCEPROP 1 LAST PATH I7
J 0
(-2875 875);
DISPLAY 0.872340 (-2875 875);
PAINT AQUA (-2875 875);
DISPLAY INVISIBLE (-2875 875);
FORCEADD PICOPROBE_BXA..1
(-2400 1050);
FORCEPROP 1 LAST PART_NUMBER TP33
J 0
(-2550 1203);
DISPLAY 0.723404 (-2550 1203);
PAINT GREEN (-2550 1203);
DISPLAY INVISIBLE (-2550 1203);
FORCEPROP 2 LAST PART_TYPE SMLF
J 0
(-2546 1346);
DISPLAY 1.021277 (-2546 1346);
FORCEPROP 1 LAST MATERIAL EMPTY
J 0
(-2554 1155);
DISPLAY 0.723404 (-2554 1155);
PAINT GREEN (-2554 1155);
FORCEPROP 2 LAST VALUE DELTA-L 4.0
J 0
(-2546 1296);
DISPLAY 1.021277 (-2546 1296);
FORCEPROP 1 LAST LOCATION J68
J 0
(-2550 1250);
DISPLAY 0.723404 (-2550 1250);
PAINT GREEN (-2550 1250);
FORCEPROP 0 LASTPIN (-2100 1050) $PN 1
J 0
(-2090 1060);
DISPLAY 0.680851 (-2090 1060);
PAINT MONO (-2090 1060);
FORCEPROP 0 LASTPIN (-2100 1100) $PN 2
J 0
(-2090 1110);
DISPLAY 0.680851 (-2090 1110);
PAINT MONO (-2090 1110);
FORCEPROP 0 LASTPIN (-2700 1100) $PN 3
J 2
(-2710 1110);
DISPLAY 0.680851 (-2710 1110);
PAINT MONO (-2710 1110);
FORCEPROP 1 LAST NEEDS_NO_SIZE TRUE
J 0
(-2400 1050);
DISPLAY 0.723404 (-2400 1050);
PAINT GREEN (-2400 1050);
DISPLAY INVISIBLE (-2400 1050);
FORCEPROP 1 LAST CDS_LMAN_SYM_OUTLINE -150,100,150,-100
J 0
(-2400 1050);
DISPLAY 0.468085 (-2400 1050);
PAINT GREEN (-2400 1050);
DISPLAY INVISIBLE (-2400 1050);
FORCEPROP 2 LAST CDS_LIB pure_quanta
J 0
(-2400 1050);
DISPLAY INVISIBLE (-2400 1050);
FORCEPROP 1 LAST PATH I8
J 0
(-2400 1050);
DISPLAY 0.723404 (-2400 1050);
PAINT GREEN (-2400 1050);
DISPLAY INVISIBLE (-2400 1050);
FORCEPROP 0 LAST $SEC 1
J 0
(-2525 1400);
DISPLAY 0.680851 (-2525 1400);
PAINT MONO (-2525 1400);
DISPLAY INVISIBLE (-2525 1400);
FORCEPROP 0 LAST CDS_SEC 1
J 0
(-2525 1400);
DISPLAY 1.021277 (-2525 1400);
DISPLAY INVISIBLE (-2525 1400);
FORCEADD UNIVERSAL_GND..1
(-2950 1450);
FORCEPROP 3 LASTPIN (-2950 1500) SIG_NAME DELTA_L_GND_1\g
J 0
(-2940 1510);
DISPLAY 0.659574 (-2940 1510);
PAINT MONO (-2940 1510);
DISPLAY INVISIBLE (-2940 1510);
FORCEPROP 1 LAST HDL_POWER DELTA_L_GND_1
J 1
(-2925 1375);
DISPLAY 0.872340 (-2925 1375);
PAINT GREEN (-2925 1375);
FORCEPROP 2 LAST CDS_LIB logical_power
J 0
(-2950 1450);
DISPLAY INVISIBLE (-2950 1450);
FORCEPROP 1 LAST PATH I9
J 0
(-2875 1450);
DISPLAY 0.872340 (-2875 1450);
PAINT AQUA (-2875 1450);
DISPLAY INVISIBLE (-2875 1450);
FORCEADD QUANTA_TITLE_BLOCK_C..1
(5425 -1025);
FORCEPROP 0 LAST CDS_CON_LAST_MODIFIED Fri Aug 25 14:05:28 2023
J 0
(3540 -1010);
PAINT MONO (3540 -1010);
DISPLAY INVISIBLE (3540 -1010);
FORCEPROP 2 LAST CUSTOM_TXT_CDS <XR_PAGE_TITLE>
J 0
(-2465 4225);
DISPLAY 0.638298 (-2465 4225);
PAINT PINK (-2465 4225);
DISPLAY INVISIBLE (-2465 4225);
FORCEPROP 2 LAST CUSTOM_TXT_CDS <CON_LAST_MODIFIED>
J 0
(3540 -1010);
DISPLAY 0.978723 (3540 -1010);
FORCEPROP 2 LAST CUSTOM_TXT_CDS <Q_REV>
J 0
(5241 -922);
DISPLAY 1.212766 (5241 -922);
FORCEPROP 2 LAST CUSTOM_TXT_CDS <CON_PAGE_NUM> OF <CON_TOTAL_PAGES>
J 0
(4979 -1007);
DISPLAY 0.978723 (4979 -1007);
FORCEPROP 2 LAST CUSTOM_TXT_CDS <Q_PROJ>
J 0
(3043 -923);
DISPLAY 1.212766 (3043 -923);
FORCEPROP 2 LAST CUSTOM_TXT_CDS <Q_NUMBER>
J 0
(4022 -922);
DISPLAY 1.212766 (4022 -922);
FORCEPROP 2 LAST CUSTOM_TXT_CDS <NAME_1>
J 0
(2250 -850);
FORCEPROP 2 LAST CUSTOM_TXT_CDS <NAME_2>
J 0
(2250 -975);
FORCEPROP 1 LAST Q_TITLE DELTA L
J 0
(-3841 -974);
DISPLAY 2.446809 (-3841 -974);
PAINT GREEN (-3841 -974);
FORCEPROP 1 LAST Q_DEPT 
J 1
(1662 -976);
DISPLAY 1.957447 (1662 -976);
PAINT GREEN (1662 -976);
FORCEPROP 2 LAST CDS_LIB pure_quanta
J 0
(5425 -1025);
PAINT MONO (5425 -1025);
DISPLAY INVISIBLE (5425 -1025);
FORCEPROP 1 LAST CDS_LMAN_SYM_OUTLINE -9475,6775,100,-125
J 0
(5425 -1025);
DISPLAY 0.468085 (5425 -1025);
PAINT GREEN (5425 -1025);
DISPLAY INVISIBLE (5425 -1025);
FORCEPROP 1 LAST COMMENT_BODY TRUE
J 0
(5437 -1038);
DISPLAY 0.978723 (5437 -1038);
PAINT GREEN (5437 -1038);
DISPLAY INVISIBLE (5437 -1038);
FORCEPROP 2 LAST PAGE_BORDER TRUE
J 0
(-2465 4225);
DISPLAY 0.638298 (-2465 4225);
PAINT PINK (-2465 4225);
DISPLAY INVISIBLE (-2465 4225);
FORCEPROP 2 LAST CDS_XR_PAGE_TITLE CR-308 : @S9S_MB_2U_LIB.S9S_MB_2U(SCH_1):PAGE308
J 0
(-2465 4225);
DISPLAY 0.638298 (-2465 4225);
PAINT PINK (-2465 4225);
DISPLAY INVISIBLE (-2465 4225);
WIRE 16 -1 (-2900 -475)(-2900 -300);
WIRE 16 -1 (-2900 100)(-2900 275);
WIRE 16 -1 (-2950 925)(-2950 1100);
WIRE 16 -1 (-2950 1500)(-2950 1675);
WIRE 16 -1 (-2950 2350)(-2950 2525);
WIRE 16 -1 (-2950 2925)(-2950 3100);
WIRE 16 -1 (-2950 3825)(-2950 4000);
WIRE 16 -1 (-2950 4400)(-2950 4575);
WIRE 16 -1 (250 -425)(250 -350);
WIRE 16 -1 (250 150)(250 225);
WIRE 16 -1 (1300 -450)(1300 -275);
WIRE 16 -1 (1300 125)(1300 300);
WIRE 16 -1 (4450 -400)(4450 -325);
WIRE 16 -1 (4450 175)(4450 250);
WIRE 16 -1 (200 975)(200 1050);
WIRE 16 -1 (200 1550)(200 1625);
WIRE 16 -1 (200 2400)(200 2475);
WIRE 16 -1 (1225 925)(1225 1100);
WIRE 16 -1 (1225 1500)(1225 1675);
WIRE 16 -1 (1225 2350)(1225 2525);
WIRE 16 -1 (200 2975)(200 3050);
WIRE 16 -1 (200 3875)(200 3950);
WIRE 16 -1 (225 4450)(225 4525);
WIRE 16 -1 (1225 2925)(1225 3100);
WIRE 16 -1 (1225 3825)(1225 4000);
WIRE 16 -1 (1225 4400)(1225 4575);
WIRE 16 -1 (4375 975)(4375 1050);
WIRE 16 -1 (4375 1550)(4375 1625);
WIRE 16 -1 (4375 2400)(4375 2475);
WIRE 16 -1 (4375 2975)(4375 3050);
WIRE 16 -1 (4375 3875)(4375 3950);
WIRE 16 -1 (4375 4450)(4375 4525);
WIRE 16 -1 (4125 4525)(4375 4525);
WIRE 16 -1 (4125 3950)(4375 3950);
WIRE 16 -1 (4125 3050)(4375 3050);
WIRE 16 -1 (4125 2475)(4375 2475);
WIRE 16 -1 (4125 1625)(4375 1625);
WIRE 16 -1 (4125 1050)(4375 1050);
WIRE 16 -1 (3525 4525)(2075 4525);
FORCEPROP 0 LAST CDS_PHYS_NET_NAME DELTA_L_85_10INCH_TOP_DP
J 0
(2115 4565);
PAINT MONO (2115 4565);
DISPLAY INVISIBLE (2115 4565);
FORCEPROP 2 LAST SIG_NAME DELTA_L_85_10INCH_TOP_DP
J 0
(2390 4535);
DISPLAY 0.638298 (2390 4535);
PAINT WHITE (2390 4535);
WIRE 16 -1 (3525 4575)(2075 4575);
FORCEPROP 0 LAST CDS_PHYS_NET_NAME DELTA_L_85_10INCH_TOP_DN
J 0
(2115 4615);
PAINT MONO (2115 4615);
DISPLAY INVISIBLE (2115 4615);
FORCEPROP 2 LAST SIG_NAME DELTA_L_85_10INCH_TOP_DN
J 0
(2390 4585);
DISPLAY 0.638298 (2390 4585);
PAINT WHITE (2390 4585);
WIRE 16 -1 (-25 4525)(225 4525);
WIRE 16 -1 (1225 4575)(1475 4575);
WIRE 16 -1 (3525 2525)(2075 2525);
FORCEPROP 0 LAST CDS_PHYS_NET_NAME DELTA_L_85_10INCH_IN2_DN
J 0
(2115 2565);
PAINT MONO (2115 2565);
DISPLAY INVISIBLE (2115 2565);
FORCEPROP 2 LAST SIG_NAME DELTA_L_85_10INCH_IN2_DN
J 0
(2390 2535);
DISPLAY 0.638298 (2390 2535);
PAINT WHITE (2390 2535);
WIRE 16 -1 (3525 2475)(2075 2475);
FORCEPROP 0 LAST CDS_PHYS_NET_NAME DELTA_L_85_10INCH_IN2_DP
J 0
(2115 2515);
PAINT MONO (2115 2515);
DISPLAY INVISIBLE (2115 2515);
FORCEPROP 2 LAST SIG_NAME DELTA_L_85_10INCH_IN2_DP
J 0
(2390 2485);
DISPLAY 0.638298 (2390 2485);
PAINT WHITE (2390 2485);
WIRE 16 -1 (3525 3100)(2075 3100);
FORCEPROP 0 LAST CDS_PHYS_NET_NAME DELTA_L_85_10INCH_IN1_DN
J 0
(2115 3140);
PAINT MONO (2115 3140);
DISPLAY INVISIBLE (2115 3140);
FORCEPROP 2 LAST SIG_NAME DELTA_L_85_10INCH_IN1_DN
J 0
(2390 3110);
DISPLAY 0.638298 (2390 3110);
PAINT WHITE (2390 3110);
WIRE 16 -1 (3525 3050)(2075 3050);
FORCEPROP 0 LAST CDS_PHYS_NET_NAME DELTA_L_85_10INCH_IN1_DP
J 0
(2115 3090);
PAINT MONO (2115 3090);
DISPLAY INVISIBLE (2115 3090);
FORCEPROP 2 LAST SIG_NAME DELTA_L_85_10INCH_IN1_DP
J 0
(2390 3060);
DISPLAY 0.638298 (2390 3060);
PAINT WHITE (2390 3060);
WIRE 16 -1 (3525 4000)(2075 4000);
FORCEPROP 0 LAST CDS_PHYS_NET_NAME DELTA_L_85_10INCH_BOT_DN
J 0
(2115 4040);
PAINT MONO (2115 4040);
DISPLAY INVISIBLE (2115 4040);
FORCEPROP 2 LAST SIG_NAME DELTA_L_85_10INCH_BOT_DN
J 0
(2390 4010);
DISPLAY 0.638298 (2390 4010);
PAINT WHITE (2390 4010);
WIRE 16 -1 (3525 3950)(2075 3950);
FORCEPROP 0 LAST CDS_PHYS_NET_NAME DELTA_L_85_10INCH_BOT_DP
J 0
(2115 3990);
PAINT MONO (2115 3990);
DISPLAY INVISIBLE (2115 3990);
FORCEPROP 2 LAST SIG_NAME DELTA_L_85_10INCH_BOT_DP
J 0
(2390 3960);
DISPLAY 0.638298 (2390 3960);
PAINT WHITE (2390 3960);
WIRE 16 -1 (3525 1100)(2075 1100);
FORCEPROP 0 LAST CDS_PHYS_NET_NAME DELTA_L_85_10INCH_IN4_DN
J 0
(2115 1140);
PAINT MONO (2115 1140);
DISPLAY INVISIBLE (2115 1140);
FORCEPROP 2 LAST SIG_NAME DELTA_L_85_10INCH_IN4_DN
J 0
(2390 1110);
DISPLAY 0.638298 (2390 1110);
PAINT WHITE (2390 1110);
WIRE 16 -1 (3525 1050)(2075 1050);
FORCEPROP 0 LAST CDS_PHYS_NET_NAME DELTA_L_85_10INCH_IN4_DP
J 0
(2115 1090);
PAINT MONO (2115 1090);
DISPLAY INVISIBLE (2115 1090);
FORCEPROP 2 LAST SIG_NAME DELTA_L_85_10INCH_IN4_DP
J 0
(2390 1060);
DISPLAY 0.638298 (2390 1060);
PAINT WHITE (2390 1060);
WIRE 16 -1 (3525 1675)(2075 1675);
FORCEPROP 0 LAST CDS_PHYS_NET_NAME DELTA_L_85_10INCH_IN3_DN
J 0
(2115 1715);
PAINT MONO (2115 1715);
DISPLAY INVISIBLE (2115 1715);
FORCEPROP 2 LAST SIG_NAME DELTA_L_85_10INCH_IN3_DN
J 0
(2390 1685);
DISPLAY 0.638298 (2390 1685);
PAINT WHITE (2390 1685);
WIRE 16 -1 (3525 1625)(2075 1625);
FORCEPROP 0 LAST CDS_PHYS_NET_NAME DELTA_L_85_10INCH_IN3_DP
J 0
(2115 1665);
PAINT MONO (2115 1665);
DISPLAY INVISIBLE (2115 1665);
FORCEPROP 2 LAST SIG_NAME DELTA_L_85_10INCH_IN3_DP
J 0
(2390 1635);
DISPLAY 0.638298 (2390 1635);
PAINT WHITE (2390 1635);
WIRE 16 -1 (1225 4000)(1475 4000);
WIRE 16 -1 (1225 3100)(1475 3100);
WIRE 16 -1 (-50 3950)(200 3950);
WIRE 16 -1 (-50 3050)(200 3050);
WIRE 16 -1 (-50 2475)(200 2475);
WIRE 16 -1 (1225 2525)(1475 2525);
WIRE 16 -1 (1225 1675)(1475 1675);
WIRE 16 -1 (1225 1100)(1475 1100);
WIRE 16 -1 (-50 1625)(200 1625);
WIRE 16 -1 (-50 1050)(200 1050);
WIRE 16 -1 (4200 -325)(4450 -325);
WIRE 16 -1 (4200 250)(4450 250);
WIRE 16 -1 (3600 -275)(2150 -275);
FORCEPROP 0 LAST CDS_PHYS_NET_NAME DELTA_L_85_10INCH_IN6_DN
J 0
(2190 -235);
PAINT MONO (2190 -235);
DISPLAY INVISIBLE (2190 -235);
FORCEPROP 2 LAST SIG_NAME DELTA_L_85_10INCH_IN6_DN
J 0
(2465 -265);
DISPLAY 0.638298 (2465 -265);
PAINT WHITE (2465 -265);
WIRE 16 -1 (3600 -325)(2150 -325);
FORCEPROP 0 LAST CDS_PHYS_NET_NAME DELTA_L_85_10INCH_IN6_DP
J 0
(2190 -285);
PAINT MONO (2190 -285);
DISPLAY INVISIBLE (2190 -285);
FORCEPROP 2 LAST SIG_NAME DELTA_L_85_10INCH_IN6_DP
J 0
(2465 -315);
DISPLAY 0.638298 (2465 -315);
PAINT WHITE (2465 -315);
WIRE 16 -1 (3600 300)(2150 300);
FORCEPROP 0 LAST CDS_PHYS_NET_NAME DELTA_L_85_10INCH_IN5_DN
J 0
(2190 340);
PAINT MONO (2190 340);
DISPLAY INVISIBLE (2190 340);
FORCEPROP 2 LAST SIG_NAME DELTA_L_85_10INCH_IN5_DN
J 0
(2465 310);
DISPLAY 0.638298 (2465 310);
PAINT WHITE (2465 310);
WIRE 16 -1 (3600 250)(2150 250);
FORCEPROP 0 LAST CDS_PHYS_NET_NAME DELTA_L_85_10INCH_IN5_DP
J 0
(2190 290);
PAINT MONO (2190 290);
DISPLAY INVISIBLE (2190 290);
FORCEPROP 2 LAST SIG_NAME DELTA_L_85_10INCH_IN5_DP
J 0
(2465 260);
DISPLAY 0.638298 (2465 260);
PAINT WHITE (2465 260);
WIRE 16 -1 (1300 300)(1550 300);
WIRE 16 -1 (1300 -275)(1550 -275);
WIRE 16 -1 (0 225)(250 225);
WIRE 16 -1 (0 -350)(250 -350);
WIRE 16 -1 (-625 4525)(-2100 4525);
FORCEPROP 0 LAST CDS_PHYS_NET_NAME DELTA_L_85_5INCH_TOP_DP
J 0
(-2060 4565);
PAINT MONO (-2060 4565);
DISPLAY INVISIBLE (-2060 4565);
FORCEPROP 2 LAST SIG_NAME DELTA_L_85_5INCH_TOP_DP
J 0
(-1785 4535);
DISPLAY 0.638298 (-1785 4535);
PAINT WHITE (-1785 4535);
WIRE 16 -1 (-625 4575)(-2100 4575);
FORCEPROP 0 LAST CDS_PHYS_NET_NAME DELTA_L_85_5INCH_TOP_DN
J 0
(-2060 4615);
PAINT MONO (-2060 4615);
DISPLAY INVISIBLE (-2060 4615);
FORCEPROP 2 LAST SIG_NAME DELTA_L_85_5INCH_TOP_DN
J 0
(-1785 4585);
DISPLAY 0.638298 (-1785 4585);
PAINT WHITE (-1785 4585);
WIRE 16 -1 (-2950 4575)(-2700 4575);
WIRE 16 -1 (-650 4000)(-2100 4000);
FORCEPROP 0 LAST CDS_PHYS_NET_NAME DELTA_L_85_5INCH_BOT_DN
J 0
(-2060 4040);
PAINT MONO (-2060 4040);
DISPLAY INVISIBLE (-2060 4040);
FORCEPROP 2 LAST SIG_NAME DELTA_L_85_5INCH_BOT_DN
J 0
(-1785 4010);
DISPLAY 0.638298 (-1785 4010);
PAINT WHITE (-1785 4010);
WIRE 16 -1 (-650 3950)(-2100 3950);
FORCEPROP 0 LAST CDS_PHYS_NET_NAME DELTA_L_85_5INCH_BOT_DP
J 0
(-2060 3990);
PAINT MONO (-2060 3990);
DISPLAY INVISIBLE (-2060 3990);
FORCEPROP 2 LAST SIG_NAME DELTA_L_85_5INCH_BOT_DP
J 0
(-1785 3960);
DISPLAY 0.638298 (-1785 3960);
PAINT WHITE (-1785 3960);
WIRE 16 -1 (-650 3100)(-2100 3100);
FORCEPROP 0 LAST CDS_PHYS_NET_NAME DELTA_L_85_5INCH_IN1_DN
J 0
(-2060 3140);
PAINT MONO (-2060 3140);
DISPLAY INVISIBLE (-2060 3140);
FORCEPROP 2 LAST SIG_NAME DELTA_L_85_5INCH_IN1_DN
J 0
(-1785 3110);
DISPLAY 0.638298 (-1785 3110);
PAINT WHITE (-1785 3110);
WIRE 16 -1 (-650 3050)(-2100 3050);
FORCEPROP 0 LAST CDS_PHYS_NET_NAME DELTA_L_85_5INCH_IN1_DP
J 0
(-2060 3090);
PAINT MONO (-2060 3090);
DISPLAY INVISIBLE (-2060 3090);
FORCEPROP 2 LAST SIG_NAME DELTA_L_85_5INCH_IN1_DP
J 0
(-1785 3060);
DISPLAY 0.638298 (-1785 3060);
PAINT WHITE (-1785 3060);
WIRE 16 -1 (-650 2525)(-2100 2525);
FORCEPROP 0 LAST CDS_PHYS_NET_NAME DELTA_L_85_5INCH_IN2_DN
J 0
(-2060 2565);
PAINT MONO (-2060 2565);
DISPLAY INVISIBLE (-2060 2565);
FORCEPROP 2 LAST SIG_NAME DELTA_L_85_5INCH_IN2_DN
J 0
(-1785 2535);
DISPLAY 0.638298 (-1785 2535);
PAINT WHITE (-1785 2535);
WIRE 16 -1 (-650 2475)(-2100 2475);
FORCEPROP 0 LAST CDS_PHYS_NET_NAME DELTA_L_85_5INCH_IN2_DP
J 0
(-2060 2515);
PAINT MONO (-2060 2515);
DISPLAY INVISIBLE (-2060 2515);
FORCEPROP 2 LAST SIG_NAME DELTA_L_85_5INCH_IN2_DP
J 0
(-1785 2485);
DISPLAY 0.638298 (-1785 2485);
PAINT WHITE (-1785 2485);
WIRE 16 -1 (-650 1675)(-2100 1675);
FORCEPROP 0 LAST CDS_PHYS_NET_NAME DELTA_L_85_5INCH_IN3_DN
J 0
(-2060 1715);
PAINT MONO (-2060 1715);
DISPLAY INVISIBLE (-2060 1715);
FORCEPROP 2 LAST SIG_NAME DELTA_L_85_5INCH_IN3_DN
J 0
(-1785 1685);
DISPLAY 0.638298 (-1785 1685);
PAINT WHITE (-1785 1685);
WIRE 16 -1 (-650 1625)(-2100 1625);
FORCEPROP 0 LAST CDS_PHYS_NET_NAME DELTA_L_85_5INCH_IN3_DP
J 0
(-2060 1665);
PAINT MONO (-2060 1665);
DISPLAY INVISIBLE (-2060 1665);
FORCEPROP 2 LAST SIG_NAME DELTA_L_85_5INCH_IN3_DP
J 0
(-1785 1635);
DISPLAY 0.638298 (-1785 1635);
PAINT WHITE (-1785 1635);
WIRE 16 -1 (-650 1100)(-2100 1100);
FORCEPROP 0 LAST CDS_PHYS_NET_NAME DELTA_L_85_5INCH_IN4_DN
J 0
(-2060 1140);
PAINT MONO (-2060 1140);
DISPLAY INVISIBLE (-2060 1140);
FORCEPROP 2 LAST SIG_NAME DELTA_L_85_5INCH_IN4_DN
J 0
(-1785 1110);
DISPLAY 0.638298 (-1785 1110);
PAINT WHITE (-1785 1110);
WIRE 16 -1 (-650 1050)(-2100 1050);
FORCEPROP 0 LAST CDS_PHYS_NET_NAME DELTA_L_85_5INCH_IN4_DP
J 0
(-2060 1090);
PAINT MONO (-2060 1090);
DISPLAY INVISIBLE (-2060 1090);
FORCEPROP 2 LAST SIG_NAME DELTA_L_85_5INCH_IN4_DP
J 0
(-1785 1060);
DISPLAY 0.638298 (-1785 1060);
PAINT WHITE (-1785 1060);
WIRE 16 -1 (-2950 4000)(-2700 4000);
WIRE 16 -1 (-2950 3100)(-2700 3100);
WIRE 16 -1 (-2950 2525)(-2700 2525);
WIRE 16 -1 (-2950 1675)(-2700 1675);
WIRE 16 -1 (-2950 1100)(-2700 1100);
WIRE 16 -1 (-600 275)(-2050 275);
FORCEPROP 0 LAST CDS_PHYS_NET_NAME DELTA_L_85_5INCH_IN5_DN
J 0
(-2010 315);
PAINT MONO (-2010 315);
DISPLAY INVISIBLE (-2010 315);
FORCEPROP 2 LAST SIG_NAME DELTA_L_85_5INCH_IN5_DN
J 0
(-1735 285);
DISPLAY 0.638298 (-1735 285);
PAINT WHITE (-1735 285);
WIRE 16 -1 (-600 225)(-2050 225);
FORCEPROP 0 LAST CDS_PHYS_NET_NAME DELTA_L_85_5INCH_IN5_DP
J 0
(-2010 265);
PAINT MONO (-2010 265);
DISPLAY INVISIBLE (-2010 265);
FORCEPROP 2 LAST SIG_NAME DELTA_L_85_5INCH_IN5_DP
J 0
(-1735 235);
DISPLAY 0.638298 (-1735 235);
PAINT WHITE (-1735 235);
WIRE 16 -1 (-600 -300)(-2050 -300);
FORCEPROP 0 LAST CDS_PHYS_NET_NAME DELTA_L_85_5INCH_IN6_DN
J 0
(-2010 -260);
PAINT MONO (-2010 -260);
DISPLAY INVISIBLE (-2010 -260);
FORCEPROP 2 LAST SIG_NAME DELTA_L_85_5INCH_IN6_DN
J 0
(-1735 -290);
DISPLAY 0.638298 (-1735 -290);
PAINT WHITE (-1735 -290);
WIRE 16 -1 (-600 -350)(-2050 -350);
FORCEPROP 0 LAST CDS_PHYS_NET_NAME DELTA_L_85_5INCH_IN6_DP
J 0
(-2010 -310);
PAINT MONO (-2010 -310);
DISPLAY INVISIBLE (-2010 -310);
FORCEPROP 2 LAST SIG_NAME DELTA_L_85_5INCH_IN6_DP
J 0
(-1735 -340);
DISPLAY 0.638298 (-1735 -340);
PAINT WHITE (-1735 -340);
WIRE 16 -1 (-2900 275)(-2650 275);
WIRE 16 -1 (-2900 -300)(-2650 -300);
FORCENOTE
5 INCH
(-2000 5175) 0;
DISPLAY LEFT (-2000 5175);
DISPLAY 3.936170 (-2000 5175);
FORCENOTE
10 INCH
(2175 5175) 0;
DISPLAY LEFT (2175 5175);
DISPLAY 3.936170 (2175 5175);
QUIT
